FILE_TYPE = MACRO_DRAWING;
SET COLOR_WIRE YELLOW;
SET COLOR_PROP MONO;
SET COLOR_DOT WHITE;
SET COLOR_ARC YELLOW;
SET COLOR_BODY GREEN;
SET COLOR_NOTE MONO;
SET PROP_DISPLAY VALUE;
SET PAGE_NUMBER P234;
FORCEADD OFFPAGE..1
(-7650 2825);
FORCEPROP 2 LAST $XR1 233 
J 0
(-8052 2825);
DISPLAY 0.638298 (-8052 2825);
PAINT MONO (-8052 2825);
FORCEPROP 2 LAST $XR0 191 
J 0
(-7932 2825);
DISPLAY 0.638298 (-7932 2825);
PAINT MONO (-7932 2825);
FORCEPROP 2 LAST CDS_LIB mstr_standard
J 0
(-7650 2825);
PAINT MONO (-7650 2825);
DISPLAY INVISIBLE (-7650 2825);
FORCEPROP 1 LAST OFFPAGE TRUE
J 0
(-7325 2700);
PAINT GREEN (-7325 2700);
DISPLAY INVISIBLE (-7325 2700);
FORCEPROP 1 LAST COMMENT_BODY TRUE
J 0
(-7525 2725);
DISPLAY 0.872340 (-7525 2725);
PAINT PEACH (-7525 2725);
DISPLAY INVISIBLE (-7525 2725);
FORCEPROP 0 LAST TOLERANCE 1%
J 0
(-7600 2900);
PAINT SKYBLUE (-7600 2900);
DISPLAY INVISIBLE (-7600 2900);
FORCEPROP 2 LAST PATH I118
J 0
(-7900 2875);
DISPLAY 1.021277 (-7900 2875);
PAINT ORANGE (-7900 2875);
DISPLAY INVISIBLE (-7900 2875);
FORCEPROP 2 LAST BOM_COST PVPP_KLM_VR
J 0
(-8475 2900);
DISPLAY 1.042553 (-8475 2900);
PAINT WHITE (-8475 2900);
DISPLAY INVISIBLE (-8475 2900);
FORCEPROP 2 LAST ROOM PVPP_KLM_VR
J 0
(-8200 2900);
DISPLAY 1.042553 (-8200 2900);
PAINT GREEN (-8200 2900);
DISPLAY INVISIBLE (-8200 2900);
FORCEADD CAP..1
R 2
(-6300 2400);
FORCEPROP 1 LAST PACK_TYPE 0402LF
J 2
(-6350 2200);
DISPLAY 0.617021 (-6350 2200);
PAINT SKYBLUE (-6350 2200);
FORCEPROP 1 LAST PART_NUMBER A36096-046
J 2
(-6325 2250);
DISPLAY 0.617021 (-6325 2250);
PAINT BLUE (-6325 2250);
FORCEPROP 1 LAST MATERIAL EMPTY
J 2
(-6350 2300);
DISPLAY 0.617021 (-6350 2300);
PAINT RED (-6350 2300);
FORCEPROP 1 LAST TOLERANCE 10%
J 2
(-6350 2350);
DISPLAY 0.617021 (-6350 2350);
PAINT SKYBLUE (-6350 2350);
FORCEPROP 1 LAST VOLTAGE 50V
J 2
(-6350 2400);
DISPLAY 0.617021 (-6350 2400);
PAINT SKYBLUE (-6350 2400);
FORCEPROP 1 LAST VALUE 1000PF
J 2
(-6350 2450);
DISPLAY 0.617021 (-6350 2450);
PAINT SKYBLUE (-6350 2450);
FORCEPROP 1 LASTPIN (-6300 2500) $PN 1
J 2
(-6310 2480);
DISPLAY 0.617021 (-6310 2480);
PAINT WHITE (-6310 2480);
FORCEPROP 1 LASTPIN (-6300 2300) $PN 2
J 2
(-6310 2280);
DISPLAY 0.617021 (-6310 2280);
PAINT WHITE (-6310 2280);
FORCEPROP 1 LAST LOCATION C4B5
J 2
(-6350 2500);
DISPLAY 0.617021 (-6350 2500);
PAINT AQUA (-6350 2500);
FORCEPROP 0 LAST FIN VR_1P2
J 2
(-6350 2700);
PAINT ORANGE (-6350 2700);
DISPLAY INVISIBLE (-6350 2700);
FORCEPROP 0 LAST REUSE_ID 1
J 2
(-6350 2600);
DISPLAY 1.042553 (-6350 2600);
PAINT ORANGE (-6350 2600);
DISPLAY INVISIBLE (-6350 2600);
FORCEPROP 2 LAST CDS_SEC 1
J 2
(-6350 2600);
DISPLAY 1.042553 (-6350 2600);
PAINT ORANGE (-6350 2600);
DISPLAY INVISIBLE (-6350 2600);
FORCEPROP 2 LAST $SEC 1
J 2
(-6350 2600);
DISPLAY 0.680851 (-6350 2600);
PAINT MONO (-6350 2600);
DISPLAY INVISIBLE (-6350 2600);
FORCEPROP 1 LAST PATH I129
J 2
(-6350 2550);
DISPLAY 0.978723 (-6350 2550);
PAINT WHITE (-6350 2550);
DISPLAY INVISIBLE (-6350 2550);
FORCEPROP 2 LAST CDS_LOCATION C4B5
J 2
(-6350 2500);
DISPLAY 0.617021 (-6350 2500);
PAINT AQUA (-6350 2500);
DISPLAY INVISIBLE (-6350 2500);
FORCEPROP 2 LAST CDS_LIB mstr_discrete
J 2
(-6300 2400);
PAINT MONO (-6300 2400);
DISPLAY INVISIBLE (-6300 2400);
FORCEPROP 2 LAST BOM_COST PVPP_KLM_VR
J 2
(-6300 2400);
PAINT WHITE (-6300 2400);
DISPLAY INVISIBLE (-6300 2400);
FORCEPROP 2 LAST ROOM PVPP_KLM_VR
J 2
(-6300 2400);
PAINT GREEN (-6300 2400);
DISPLAY INVISIBLE (-6300 2400);
FORCEADD GND..1
(-3875 475);
FORCEPROP 3 LASTPIN (-3875 525) SIG_NAME GND\g
J 0
(-3865 535);
DISPLAY 0.659574 (-3865 535);
PAINT MONO (-3865 535);
DISPLAY INVISIBLE (-3865 535);
FORCEPROP 1 LAST HDL_POWER GND
J 0
(-3875 700);
DISPLAY 0.893617 (-3875 700);
PAINT GREEN (-3875 700);
DISPLAY INVISIBLE (-3875 700);
FORCEPROP 2 LAST CDS_LIB mstr_symbols
J 0
(-3875 550);
PAINT MONO (-3875 550);
DISPLAY INVISIBLE (-3875 550);
FORCEPROP 1 LAST VOLTAGE 0
J 0
(-3875 550);
PAINT SKYBLUE (-3875 550);
DISPLAY INVISIBLE (-3875 550);
FORCEPROP 1 LAST SIZE 1B
J 0
(-3800 500);
DISPLAY 0.893617 (-3800 500);
PAINT GREEN (-3800 500);
DISPLAY INVISIBLE (-3800 500);
FORCEPROP 1 LAST BODY_TYPE PLUMBING
J 0
(-3920 432);
DISPLAY 0.340426 (-3920 432);
PAINT GREEN (-3920 432);
DISPLAY INVISIBLE (-3920 432);
FORCEPROP 1 LAST PATH I138
J 0
(-3800 475);
DISPLAY 0.872340 (-3800 475);
PAINT AQUA (-3800 475);
DISPLAY INVISIBLE (-3800 475);
FORCEPROP 2 LAST ROOM PVPP_KLM_VR
J 0
(-4525 625);
PAINT GREEN (-4525 625);
DISPLAY INVISIBLE (-4525 625);
FORCEPROP 2 LAST BOM_COST PVPP_KLM_VR
J 0
(-4775 625);
DISPLAY 1.042553 (-4775 625);
PAINT WHITE (-4775 625);
DISPLAY INVISIBLE (-4775 625);
FORCEADD CAP..1
(-3875 725);
FORCEPROP 1 LAST VALUE 1000PF
J 0
(-3825 775);
DISPLAY 0.617021 (-3825 775);
PAINT SKYBLUE (-3825 775);
FORCEPROP 1 LAST PACK_TYPE 0402LF
J 0
(-3825 575);
DISPLAY 0.617021 (-3825 575);
PAINT SKYBLUE (-3825 575);
FORCEPROP 1 LAST PART_NUMBER A36096-046
J 0
(-3825 525);
DISPLAY 0.617021 (-3825 525);
PAINT BLUE (-3825 525);
FORCEPROP 1 LAST VOLTAGE 50V
J 0
(-3825 725);
DISPLAY 0.617021 (-3825 725);
PAINT SKYBLUE (-3825 725);
FORCEPROP 1 LAST MATERIAL X7R
J 0
(-3825 625);
DISPLAY 0.617021 (-3825 625);
PAINT SKYBLUE (-3825 625);
FORCEPROP 1 LAST LOCATION C4B8
J 0
(-3825 825);
DISPLAY 0.617021 (-3825 825);
PAINT AQUA (-3825 825);
FORCEPROP 1 LAST TOLERANCE 10%
J 0
(-3825 675);
DISPLAY 0.617021 (-3825 675);
PAINT SKYBLUE (-3825 675);
FORCEPROP 1 LASTPIN (-3875 625) $PN 2
J 0
(-3865 605);
DISPLAY 0.617021 (-3865 605);
PAINT WHITE (-3865 605);
FORCEPROP 1 LASTPIN (-3875 825) $PN 1
J 0
(-3865 805);
DISPLAY 0.617021 (-3865 805);
PAINT WHITE (-3865 805);
FORCEPROP 2 LAST CDS_LOCATION C4B8
J 0
(-3825 825);
DISPLAY 0.617021 (-3825 825);
PAINT AQUA (-3825 825);
DISPLAY INVISIBLE (-3825 825);
FORCEPROP 1 LAST PATH I139
J 0
(-3825 875);
DISPLAY 0.978723 (-3825 875);
PAINT WHITE (-3825 875);
DISPLAY INVISIBLE (-3825 875);
FORCEPROP 2 LAST $SEC 1
J 2
(-3825 925);
DISPLAY 0.680851 (-3825 925);
PAINT MONO (-3825 925);
DISPLAY INVISIBLE (-3825 925);
FORCEPROP 2 LAST CDS_SEC 1
J 2
(-3825 925);
DISPLAY 1.042553 (-3825 925);
PAINT ORANGE (-3825 925);
DISPLAY INVISIBLE (-3825 925);
FORCEPROP 2 LAST REUSE_ID 17
J 0
(-3825 925);
DISPLAY 1.042553 (-3825 925);
PAINT ORANGE (-3825 925);
DISPLAY INVISIBLE (-3825 925);
FORCEPROP 2 LAST BOM_COST PVPP_KLM_VR
J 0
(-3875 725);
PAINT WHITE (-3875 725);
DISPLAY INVISIBLE (-3875 725);
FORCEPROP 2 LAST CDS_LIB mstr_discrete
J 2
(-3875 725);
PAINT MONO (-3875 725);
DISPLAY INVISIBLE (-3875 725);
FORCEPROP 2 LAST ROOM PVPP_KLM_VR
J 0
(-3875 725);
PAINT GREEN (-3875 725);
DISPLAY INVISIBLE (-3875 725);
FORCEADD P3V3_STBY..1
(-4225 1525);
FORCEPROP 3 LASTPIN (-4225 1475) SIG_NAME P3V3_STBY\g
J 0
(-4215 1485);
DISPLAY 0.659574 (-4215 1485);
PAINT MONO (-4215 1485);
DISPLAY INVISIBLE (-4215 1485);
FORCEPROP 1 LAST VOLTAGE +3.3V
J 0
(-4025 1675);
DISPLAY 1.021277 (-4025 1675);
PAINT SKYBLUE (-4025 1675);
DISPLAY INVISIBLE (-4025 1675);
FORCEPROP 1 LAST SIZE 1B
J 0
(-4180 1547);
DISPLAY 0.340426 (-4180 1547);
PAINT GREEN (-4180 1547);
DISPLAY INVISIBLE (-4180 1547);
FORCEPROP 2 LAST CDS_LIB mstr_symbols
J 0
(-4225 1525);
PAINT MONO (-4225 1525);
DISPLAY INVISIBLE (-4225 1525);
FORCEPROP 1 LAST PATH I142
J 0
(-4180 1527);
DISPLAY 0.340426 (-4180 1527);
PAINT GREEN (-4180 1527);
DISPLAY INVISIBLE (-4180 1527);
FORCEPROP 1 LAST BODY_TYPE PLUMBING
J 0
(-4270 1482);
DISPLAY 0.340426 (-4270 1482);
PAINT GREEN (-4270 1482);
DISPLAY INVISIBLE (-4270 1482);
FORCEPROP 1 LAST HDL_POWER P3V3_STBY
J 0
(-4525 1400);
DISPLAY 0.872340 (-4525 1400);
PAINT ORANGE (-4525 1400);
DISPLAY INVISIBLE (-4525 1400);
FORCEADD RES..2
(-4225 1250);
FORCEPROP 1 LAST LOCATION R4B10
J 0
(-4180 1375);
DISPLAY 0.617021 (-4180 1375);
PAINT AQUA (-4180 1375);
FORCEPROP 1 LAST PART_NUMBER G21796-026
J 0
(-4185 1125);
DISPLAY 0.617021 (-4185 1125);
PAINT BLUE (-4185 1125);
FORCEPROP 1 LAST VALUE 1.00K
J 0
(-4180 1325);
DISPLAY 0.617021 (-4180 1325);
PAINT SKYBLUE (-4180 1325);
FORCEPROP 1 LAST PACK_TYPE 0402
J 0
(-4185 1075);
DISPLAY 0.617021 (-4185 1075);
PAINT SKYBLUE (-4185 1075);
FORCEPROP 1 LAST MATERIAL CHIP
J 0
(-4185 1175);
DISPLAY 0.617021 (-4185 1175);
PAINT SKYBLUE (-4185 1175);
FORCEPROP 1 LAST WATTAGE 1/16W
J 0
(-4185 1225);
DISPLAY 0.617021 (-4185 1225);
PAINT SKYBLUE (-4185 1225);
FORCEPROP 1 LASTPIN (-4225 1350) $PN 1
J 0
(-4220 1312);
DISPLAY 0.617021 (-4220 1312);
PAINT WHITE (-4220 1312);
FORCEPROP 1 LAST TOLERANCE 1%
J 0
(-4180 1275);
DISPLAY 0.617021 (-4180 1275);
PAINT SKYBLUE (-4180 1275);
FORCEPROP 1 LASTPIN (-4225 1150) $PN 2
J 0
(-4220 1160);
DISPLAY 0.617021 (-4220 1160);
PAINT WHITE (-4220 1160);
FORCEPROP 2 LAST ROOM PVPP_KLM_VR
J 0
(-4165 1415);
PAINT GREEN (-4165 1415);
DISPLAY INVISIBLE (-4165 1415);
FORCEPROP 1 LAST PATH I143
J 0
(-4175 1425);
DISPLAY 0.978723 (-4175 1425);
PAINT WHITE (-4175 1425);
DISPLAY INVISIBLE (-4175 1425);
FORCEPROP 2 LAST CDS_LOCATION R4B10
J 0
(-4180 1375);
DISPLAY 0.617021 (-4180 1375);
PAINT AQUA (-4180 1375);
DISPLAY INVISIBLE (-4180 1375);
FORCEPROP 2 LAST SEC 1
J 0
(-4175 1475);
DISPLAY 0.680851 (-4175 1475);
PAINT MONO (-4175 1475);
DISPLAY INVISIBLE (-4175 1475);
FORCEPROP 2 LAST SEC_TYPE 0402
J 0
(-4175 1475);
DISPLAY 1.042553 (-4175 1475);
PAINT ORANGE (-4175 1475);
DISPLAY INVISIBLE (-4175 1475);
FORCEPROP 2 LAST BOM_COST PVPP_KLM_VR
J 0
(-4165 1440);
DISPLAY 1.042553 (-4165 1440);
PAINT WHITE (-4165 1440);
DISPLAY INVISIBLE (-4165 1440);
FORCEPROP 2 LAST REUSE_ID 21
J 0
(-4175 1475);
DISPLAY 1.042553 (-4175 1475);
PAINT ORANGE (-4175 1475);
DISPLAY INVISIBLE (-4175 1475);
FORCEPROP 2 LAST CDS_LIB mstr_discrete
J 0
(-4225 1250);
PAINT MONO (-4225 1250);
DISPLAY INVISIBLE (-4225 1250);
FORCEADD CAP..1
(-5650 2400);
FORCEPROP 1 LAST TOLERANCE 10%
J 0
(-5575 2350);
DISPLAY 0.617021 (-5575 2350);
PAINT SKYBLUE (-5575 2350);
FORCEPROP 1 LAST PART_NUMBER E15431-003
J 0
(-5625 2250);
DISPLAY 0.617021 (-5625 2250);
PAINT BLUE (-5625 2250);
FORCEPROP 1 LAST PACK_TYPE 0603
J 0
(-5600 2300);
DISPLAY 0.617021 (-5600 2300);
PAINT SKYBLUE (-5600 2300);
FORCEPROP 1 LASTPIN (-5650 2300) $PN 2
J 0
(-5640 2280);
DISPLAY 0.617021 (-5640 2280);
PAINT ORANGE (-5640 2280);
FORCEPROP 1 LAST VOLTAGE 6.3V
J 0
(-5575 2400);
DISPLAY 0.617021 (-5575 2400);
PAINT SKYBLUE (-5575 2400);
FORCEPROP 1 LAST VALUE 4.7UF
J 0
(-5600 2450);
DISPLAY 0.617021 (-5600 2450);
PAINT SKYBLUE (-5600 2450);
FORCEPROP 1 LAST LOCATION C6L12
J 0
(-5600 2500);
DISPLAY 0.617021 (-5600 2500);
PAINT AQUA (-5600 2500);
FORCEPROP 1 LASTPIN (-5650 2500) $PN 1
J 0
(-5640 2480);
DISPLAY 0.617021 (-5640 2480);
PAINT ORANGE (-5640 2480);
FORCEPROP 1 LAST MATERIAL X6S
J 0
(-5600 2200);
DISPLAY 0.617021 (-5600 2200);
PAINT SKYBLUE (-5600 2200);
FORCEPROP 0 LAST CONFIG 078.47521.08BD
J 0
(-5775 2175);
DISPLAY 0.638298 (-5775 2175);
PAINT BROWN (-5775 2175);
DISPLAY BOTH (-5775 2175);
FORCEPROP 2 LAST CDS_LIB mstr_discrete
J 0
(-5650 2400);
PAINT MONO (-5650 2400);
DISPLAY INVISIBLE (-5650 2400);
FORCEPROP 2 LAST ROOM PVPP_KLM_VR
J 0
(-5600 2525);
PAINT GREEN (-5600 2525);
DISPLAY INVISIBLE (-5600 2525);
FORCEPROP 1 LAST PATH I144
J 0
(-5600 2550);
DISPLAY 0.978723 (-5600 2550);
PAINT WHITE (-5600 2550);
DISPLAY INVISIBLE (-5600 2550);
FORCEPROP 2 LAST BOM_COST PVPP_KLM_VR
J 0
(-5600 2550);
DISPLAY 1.042553 (-5600 2550);
PAINT WHITE (-5600 2550);
DISPLAY INVISIBLE (-5600 2550);
FORCEPROP 2 LAST SEC_TYPE 0603
J 0
(-5600 2600);
DISPLAY 1.021277 (-5600 2600);
PAINT ORANGE (-5600 2600);
DISPLAY INVISIBLE (-5600 2600);
FORCEPROP 2 LAST REUSE_ID 26
J 0
(-5600 2600);
DISPLAY 1.042553 (-5600 2600);
PAINT ORANGE (-5600 2600);
DISPLAY INVISIBLE (-5600 2600);
FORCEPROP 2 LAST SEC 1
J 0
(-5600 2600);
PAINT MONO (-5600 2600);
DISPLAY INVISIBLE (-5600 2600);
FORCEADD CAP..1
(-5075 2175);
FORCEPROP 1 LAST LOCATION C4B6
J 0
(-5025 2275);
DISPLAY 0.617021 (-5025 2275);
PAINT AQUA (-5025 2275);
FORCEPROP 1 LAST TOLERANCE 10%
J 0
(-5000 2125);
DISPLAY 0.617021 (-5000 2125);
PAINT SKYBLUE (-5000 2125);
FORCEPROP 1 LAST VOLTAGE 16V
J 0
(-5000 2175);
DISPLAY 0.617021 (-5000 2175);
PAINT SKYBLUE (-5000 2175);
FORCEPROP 1 LAST VALUE 0.027UF
J 0
(-5025 2225);
DISPLAY 0.617021 (-5025 2225);
PAINT SKYBLUE (-5025 2225);
FORCEPROP 1 LASTPIN (-5075 2075) $PN 2
J 0
(-5065 2055);
DISPLAY 0.617021 (-5065 2055);
PAINT ORANGE (-5065 2055);
FORCEPROP 1 LASTPIN (-5075 2275) $PN 1
J 0
(-5065 2255);
DISPLAY 0.617021 (-5065 2255);
PAINT ORANGE (-5065 2255);
FORCEPROP 1 LAST PACK_TYPE 0402
J 0
(-5025 2075);
DISPLAY 0.617021 (-5025 2075);
PAINT SKYBLUE (-5025 2075);
FORCEPROP 1 LAST MATERIAL X7R
J 0
(-5025 1975);
DISPLAY 0.617021 (-5025 1975);
PAINT SKYBLUE (-5025 1975);
FORCEPROP 1 LAST PART_NUMBER A36096-129
J 0
(-5050 2025);
DISPLAY 0.617021 (-5050 2025);
PAINT BLUE (-5050 2025);
FORCEPROP 1 LAST PATH I146
J 0
(-5025 2325);
DISPLAY 0.978723 (-5025 2325);
PAINT WHITE (-5025 2325);
DISPLAY INVISIBLE (-5025 2325);
FORCEPROP 0 LAST SEC 1
J 0
(-5025 2325);
DISPLAY 0.680851 (-5025 2325);
PAINT MONO (-5025 2325);
DISPLAY INVISIBLE (-5025 2325);
FORCEPROP 2 LAST REUSE_ID 26
J 0
(-5025 2375);
DISPLAY 1.042553 (-5025 2375);
PAINT ORANGE (-5025 2375);
DISPLAY INVISIBLE (-5025 2375);
FORCEPROP 2 LAST BOM_COST PVPP_KLM_VR
J 0
(-5025 2325);
DISPLAY 1.042553 (-5025 2325);
PAINT WHITE (-5025 2325);
DISPLAY INVISIBLE (-5025 2325);
FORCEPROP 2 LAST SEC_TYPE 0402
J 0
(-5025 2375);
DISPLAY 1.021277 (-5025 2375);
PAINT ORANGE (-5025 2375);
DISPLAY INVISIBLE (-5025 2375);
FORCEPROP 2 LAST ROOM PVPP_KLM_VR
J 0
(-5025 2300);
PAINT GREEN (-5025 2300);
DISPLAY INVISIBLE (-5025 2300);
FORCEPROP 2 LAST CDS_LOCATION C4B6
J 0
(-5025 2275);
DISPLAY 0.617021 (-5025 2275);
PAINT AQUA (-5025 2275);
DISPLAY INVISIBLE (-5025 2275);
FORCEPROP 2 LAST CDS_LIB mstr_discrete
J 0
(-5075 2175);
PAINT MONO (-5075 2175);
DISPLAY INVISIBLE (-5075 2175);
FORCEADD GND..1
(-5100 3900);
FORCEPROP 3 LASTPIN (-5100 3950) SIG_NAME GND\g
J 0
(-5090 3960);
DISPLAY 0.659574 (-5090 3960);
PAINT MONO (-5090 3960);
DISPLAY INVISIBLE (-5090 3960);
FORCEPROP 1 LAST HDL_POWER GND
J 0
(-5100 4050);
DISPLAY 0.872340 (-5100 4050);
PAINT GREEN (-5100 4050);
DISPLAY INVISIBLE (-5100 4050);
FORCEPROP 1 LAST VOLTAGE 0
J 0
(-5100 3900);
PAINT SKYBLUE (-5100 3900);
DISPLAY INVISIBLE (-5100 3900);
FORCEPROP 2 LAST CDS_LIB mstr_symbols
J 0
(-5100 3900);
PAINT MONO (-5100 3900);
DISPLAY INVISIBLE (-5100 3900);
FORCEPROP 1 LAST PATH I151
J 0
(-5025 3900);
DISPLAY 0.872340 (-5025 3900);
PAINT AQUA (-5025 3900);
DISPLAY INVISIBLE (-5025 3900);
FORCEPROP 1 LAST BODY_TYPE PLUMBING
J 0
(-5145 3857);
DISPLAY 0.340426 (-5145 3857);
PAINT GREEN (-5145 3857);
DISPLAY INVISIBLE (-5145 3857);
FORCEPROP 1 LAST SIZE 1B
J 0
(-5025 3850);
DISPLAY 0.872340 (-5025 3850);
PAINT GREEN (-5025 3850);
DISPLAY INVISIBLE (-5025 3850);
FORCEPROP 2 LAST ROOM PVPP_KLM_VR
J 0
(-5675 3975);
DISPLAY 1.042553 (-5675 3975);
PAINT GREEN (-5675 3975);
DISPLAY INVISIBLE (-5675 3975);
FORCEPROP 2 LAST BOM_COST PVPP_KLM_VR
J 0
(-5950 3975);
DISPLAY 1.042553 (-5950 3975);
PAINT WHITE (-5950 3975);
DISPLAY INVISIBLE (-5950 3975);
FORCEADD CAP..1
(-5100 4150);
FORCEPROP 1 LAST TOLERANCE 10%
J 0
(-5050 4100);
DISPLAY 0.617021 (-5050 4100);
PAINT SKYBLUE (-5050 4100);
FORCEPROP 1 LAST MATERIAL X6S
J 0
(-5050 4050);
DISPLAY 0.617021 (-5050 4050);
PAINT SKYBLUE (-5050 4050);
FORCEPROP 1 LAST PART_NUMBER D97712-011
J 0
(-5050 4000);
DISPLAY 0.617021 (-5050 4000);
PAINT BLUE (-5050 4000);
FORCEPROP 1 LAST PACK_TYPE 0402
J 0
(-5050 3950);
DISPLAY 0.617021 (-5050 3950);
PAINT SKYBLUE (-5050 3950);
FORCEPROP 1 LAST LOCATION C6L11
J 0
(-5050 4250);
DISPLAY 0.617021 (-5050 4250);
PAINT AQUA (-5050 4250);
FORCEPROP 1 LAST VALUE 1.0UF
J 0
(-5050 4200);
DISPLAY 0.617021 (-5050 4200);
PAINT SKYBLUE (-5050 4200);
FORCEPROP 1 LAST VOLTAGE 16V
J 0
(-5050 4150);
DISPLAY 0.617021 (-5050 4150);
PAINT SKYBLUE (-5050 4150);
FORCEPROP 1 LASTPIN (-5100 4250) $PN 1
J 0
(-5090 4230);
DISPLAY 0.617021 (-5090 4230);
PAINT WHITE (-5090 4230);
FORCEPROP 1 LASTPIN (-5100 4050) $PN 2
J 0
(-5090 4030);
DISPLAY 0.617021 (-5090 4030);
PAINT WHITE (-5090 4030);
FORCEPROP 0 LAST FIN VR_1P2
J 0
(-5050 4450);
PAINT ORANGE (-5050 4450);
DISPLAY INVISIBLE (-5050 4450);
FORCEPROP 2 LAST $SEC 1
J 0
(-5050 4350);
DISPLAY 0.680851 (-5050 4350);
PAINT MONO (-5050 4350);
DISPLAY INVISIBLE (-5050 4350);
FORCEPROP 2 LAST CDS_SEC 1
J 0
(-5050 4350);
DISPLAY 1.042553 (-5050 4350);
PAINT ORANGE (-5050 4350);
DISPLAY INVISIBLE (-5050 4350);
FORCEPROP 0 LAST REUSE_ID 1
J 0
(-5050 4350);
DISPLAY 1.042553 (-5050 4350);
PAINT ORANGE (-5050 4350);
DISPLAY INVISIBLE (-5050 4350);
FORCEPROP 1 LAST PATH I152
J 0
(-5050 4300);
DISPLAY 0.978723 (-5050 4300);
PAINT WHITE (-5050 4300);
DISPLAY INVISIBLE (-5050 4300);
FORCEPROP 2 LAST CDS_LOCATION C6L11
J 0
(-5050 4250);
DISPLAY 0.617021 (-5050 4250);
PAINT AQUA (-5050 4250);
DISPLAY INVISIBLE (-5050 4250);
FORCEPROP 2 LAST ROOM PVPP_KLM_VR
J 0
(-5100 4150);
PAINT GREEN (-5100 4150);
DISPLAY INVISIBLE (-5100 4150);
FORCEPROP 2 LAST BOM_COST PVPP_KLM_VR
J 0
(-5100 4150);
PAINT WHITE (-5100 4150);
DISPLAY INVISIBLE (-5100 4150);
FORCEPROP 2 LAST CDS_LIB mstr_discrete
J 0
(-5100 4150);
PAINT MONO (-5100 4150);
DISPLAY INVISIBLE (-5100 4150);
FORCEADD P12V_STBY..1
(-7850 4500);
FORCEPROP 3 LASTPIN (-7850 4450) SIG_NAME P12V_STBY\g
J 0
(-7840 4460);
DISPLAY 0.659574 (-7840 4460);
PAINT MONO (-7840 4460);
DISPLAY INVISIBLE (-7840 4460);
FORCEPROP 1 LAST VOLTAGE 12.0V
J 0
(-7895 4457);
DISPLAY 0.340426 (-7895 4457);
PAINT SKYBLUE (-7895 4457);
DISPLAY INVISIBLE (-7895 4457);
FORCEPROP 2 LAST CDS_LIB mstr_symbols
J 0
(-7850 4500);
PAINT ORANGE (-7850 4500);
DISPLAY INVISIBLE (-7850 4500);
FORCEPROP 1 LAST SIZE 1B
J 0
(-7805 4522);
DISPLAY 0.340426 (-7805 4522);
PAINT GREEN (-7805 4522);
DISPLAY INVISIBLE (-7805 4522);
FORCEPROP 1 LAST BODY_TYPE PLUMBING
J 0
(-7895 4457);
DISPLAY 0.340426 (-7895 4457);
PAINT GREEN (-7895 4457);
DISPLAY INVISIBLE (-7895 4457);
FORCEPROP 1 LAST PATH I153
J 0
(-7805 4502);
DISPLAY 0.340426 (-7805 4502);
PAINT GREEN (-7805 4502);
DISPLAY INVISIBLE (-7805 4502);
FORCEPROP 1 LAST HDL_POWER P12V_STBY
J 0
(-8150 4375);
DISPLAY 0.872340 (-8150 4375);
PAINT ORANGE (-8150 4375);
DISPLAY INVISIBLE (-8150 4375);
FORCEADD FERRITE..1
(-7650 4300);
FORCEPROP 1 LASTPIN (-7750 4300) $PN 1
J 2
(-7715 4310);
DISPLAY 0.617021 (-7715 4310);
PAINT WHITE (-7715 4310);
FORCEPROP 1 LAST VALUE 22
J 2
(-7670 4200);
DISPLAY 0.617021 (-7670 4200);
PAINT SKYBLUE (-7670 4200);
FORCEPROP 1 LAST MATERIAL FB
J 0
(-7645 4200);
DISPLAY 0.617021 (-7645 4200);
PAINT SKYBLUE (-7645 4200);
FORCEPROP 1 LAST LOCATION FB4A1
J 0
(-7745 4355);
DISPLAY 0.617021 (-7745 4355);
PAINT AQUA (-7745 4355);
FORCEPROP 1 LASTPIN (-7550 4300) $PN 2
J 0
(-7570 4310);
DISPLAY 0.617021 (-7570 4310);
PAINT WHITE (-7570 4310);
FORCEPROP 1 LAST PACK_TYPE SM
J 0
(-7570 4200);
DISPLAY 0.617021 (-7570 4200);
PAINT SKYBLUE (-7570 4200);
FORCEPROP 1 LAST PART_NUMBER 656554-051
J 0
(-7745 4415);
DISPLAY 0.617021 (-7745 4415);
PAINT BLUE (-7745 4415);
FORCEPROP 2 LAST CDS_LIB mstr_discrete
J 0
(-7650 4300);
PAINT MONO (-7650 4300);
DISPLAY INVISIBLE (-7650 4300);
FORCEPROP 0 LAST TOLERANCE 1%
J 0
(-7725 4450);
PAINT SKYBLUE (-7725 4450);
DISPLAY INVISIBLE (-7725 4450);
FORCEPROP 2 LAST SEC_TYPE SM
J 0
(-7725 4525);
DISPLAY 1.659574 (-7725 4525);
PAINT ORANGE (-7725 4525);
DISPLAY INVISIBLE (-7725 4525);
FORCEPROP 2 LAST SEC 1
J 0
(-7725 4525);
DISPLAY 1.106383 (-7725 4525);
PAINT MONO (-7725 4525);
DISPLAY INVISIBLE (-7725 4525);
FORCEPROP 2 LAST CDS_LOCATION FB4A1
J 0
(-7745 4355);
DISPLAY 0.617021 (-7745 4355);
PAINT AQUA (-7745 4355);
DISPLAY INVISIBLE (-7745 4355);
FORCEPROP 1 LAST PATH I154
J 0
(-7745 4465);
DISPLAY 0.872340 (-7745 4465);
PAINT PURPLE (-7745 4465);
DISPLAY INVISIBLE (-7745 4465);
FORCEPROP 2 LAST ROOM PVPP_KLM_VR
J 0
(-7725 4450);
DISPLAY 1.659574 (-7725 4450);
PAINT GREEN (-7725 4450);
DISPLAY INVISIBLE (-7725 4450);
FORCEADD OFFPAGE..2
(-2475 975);
FORCEPROP 2 LAST $XR0 190 
J 0
(-2286 975);
DISPLAY 0.638298 (-2286 975);
PAINT MONO (-2286 975);
FORCEPROP 2 LAST ROOM PVPP_KLM_VR
J 0
(-2900 1050);
DISPLAY 1.042553 (-2900 1050);
PAINT GREEN (-2900 1050);
DISPLAY INVISIBLE (-2900 1050);
FORCEPROP 2 LAST PATH I156
J 0
(-2175 1025);
DISPLAY 1.021277 (-2175 1025);
PAINT ORANGE (-2175 1025);
DISPLAY INVISIBLE (-2175 1025);
FORCEPROP 0 LAST TOLERANCE 1%
J 0
(-2300 1050);
PAINT SKYBLUE (-2300 1050);
DISPLAY INVISIBLE (-2300 1050);
FORCEPROP 1 LAST OFFPAGE TRUE
J 0
(-2150 850);
PAINT GREEN (-2150 850);
DISPLAY INVISIBLE (-2150 850);
FORCEPROP 2 LAST CDS_LIB mstr_standard
J 2
(-2475 975);
PAINT MONO (-2475 975);
DISPLAY INVISIBLE (-2475 975);
FORCEPROP 1 LAST COMMENT_BODY TRUE
J 0
(-2520 880);
DISPLAY 0.872340 (-2520 880);
PAINT PEACH (-2520 880);
DISPLAY INVISIBLE (-2520 880);
FORCEPROP 2 LAST BOM_COST PVPP_KLM_VR
J 0
(-3175 1050);
DISPLAY 1.042553 (-3175 1050);
PAINT WHITE (-3175 1050);
DISPLAY INVISIBLE (-3175 1050);
FORCEADD GND..1
(-3075 1925);
FORCEPROP 3 LASTPIN (-3075 1975) SIG_NAME GND\g
J 0
(-3065 1985);
DISPLAY 0.659574 (-3065 1985);
PAINT MONO (-3065 1985);
DISPLAY INVISIBLE (-3065 1985);
FORCEPROP 1 LAST HDL_POWER GND
J 0
(-3075 2150);
DISPLAY 0.893617 (-3075 2150);
PAINT GREEN (-3075 2150);
DISPLAY INVISIBLE (-3075 2150);
FORCEPROP 2 LAST BOM_COST PVPP_KLM_VR
J 0
(-3975 2075);
DISPLAY 1.042553 (-3975 2075);
PAINT WHITE (-3975 2075);
DISPLAY INVISIBLE (-3975 2075);
FORCEPROP 2 LAST ROOM PVPP_KLM_VR
J 0
(-3725 2075);
PAINT GREEN (-3725 2075);
DISPLAY INVISIBLE (-3725 2075);
FORCEPROP 1 LAST SIZE 1B
J 0
(-3000 1950);
DISPLAY 0.893617 (-3000 1950);
PAINT GREEN (-3000 1950);
DISPLAY INVISIBLE (-3000 1950);
FORCEPROP 1 LAST PATH I157
J 0
(-3000 1925);
DISPLAY 0.872340 (-3000 1925);
PAINT AQUA (-3000 1925);
DISPLAY INVISIBLE (-3000 1925);
FORCEPROP 1 LAST BODY_TYPE PLUMBING
J 0
(-3120 1882);
DISPLAY 0.340426 (-3120 1882);
PAINT GREEN (-3120 1882);
DISPLAY INVISIBLE (-3120 1882);
FORCEPROP 2 LAST CDS_LIB mstr_symbols
J 0
(-3075 1925);
PAINT MONO (-3075 1925);
DISPLAY INVISIBLE (-3075 1925);
FORCEPROP 1 LAST VOLTAGE 0
J 0
(-3075 2000);
PAINT SKYBLUE (-3075 2000);
DISPLAY INVISIBLE (-3075 2000);
FORCEADD GND..1
(-2575 3100);
FORCEPROP 3 LASTPIN (-2575 3150) SIG_NAME GND\g
J 0
(-2565 3160);
DISPLAY 0.659574 (-2565 3160);
PAINT MONO (-2565 3160);
DISPLAY INVISIBLE (-2565 3160);
FORCEPROP 2 LAST BOM_COST PVPP_KLM_VR
J 0
(-3475 3250);
DISPLAY 1.042553 (-3475 3250);
PAINT WHITE (-3475 3250);
DISPLAY INVISIBLE (-3475 3250);
FORCEPROP 2 LAST ROOM PVPP_KLM_VR
J 0
(-3225 3250);
PAINT GREEN (-3225 3250);
DISPLAY INVISIBLE (-3225 3250);
FORCEPROP 1 LAST BODY_TYPE PLUMBING
J 0
(-2620 3057);
DISPLAY 0.340426 (-2620 3057);
PAINT GREEN (-2620 3057);
DISPLAY INVISIBLE (-2620 3057);
FORCEPROP 1 LAST PATH I161
J 0
(-2500 3100);
DISPLAY 0.872340 (-2500 3100);
PAINT AQUA (-2500 3100);
DISPLAY INVISIBLE (-2500 3100);
FORCEPROP 1 LAST SIZE 1B
J 0
(-2500 3125);
DISPLAY 0.893617 (-2500 3125);
PAINT GREEN (-2500 3125);
DISPLAY INVISIBLE (-2500 3125);
FORCEPROP 2 LAST CDS_LIB mstr_symbols
J 0
(-2575 3175);
PAINT MONO (-2575 3175);
DISPLAY INVISIBLE (-2575 3175);
FORCEPROP 1 LAST VOLTAGE 0
J 0
(-2575 3175);
PAINT SKYBLUE (-2575 3175);
DISPLAY INVISIBLE (-2575 3175);
FORCEPROP 1 LAST HDL_POWER GND
J 0
(-2575 3325);
DISPLAY 0.893617 (-2575 3325);
PAINT GREEN (-2575 3325);
DISPLAY INVISIBLE (-2575 3325);
FORCEADD RES..2
(-2575 3275);
FORCEPROP 1 LAST TOLERANCE 5%
J 0
(-2230 3350);
DISPLAY 0.617021 (-2230 3350);
PAINT SKYBLUE (-2230 3350);
FORCEPROP 1 LASTPIN (-2575 3375) $PN 1
J 0
(-2570 3337);
DISPLAY 0.617021 (-2570 3337);
PAINT WHITE (-2570 3337);
FORCEPROP 1 LASTPIN (-2575 3175) $PN 2
J 0
(-2570 3185);
DISPLAY 0.617021 (-2570 3185);
PAINT WHITE (-2570 3185);
FORCEPROP 1 LAST LOCATION R4A7
J 0
(-2455 3350);
DISPLAY 0.617021 (-2455 3350);
PAINT AQUA (-2455 3350);
FORCEPROP 1 LAST VALUE 2.2
J 0
(-2330 3350);
DISPLAY 0.617021 (-2330 3350);
PAINT SKYBLUE (-2330 3350);
FORCEPROP 1 LAST WATTAGE 1/16W
J 0
(-2460 3300);
DISPLAY 0.617021 (-2460 3300);
PAINT SKYBLUE (-2460 3300);
FORCEPROP 1 LAST PACK_TYPE 0402
J 0
(-2310 3300);
DISPLAY 0.617021 (-2310 3300);
PAINT SKYBLUE (-2310 3300);
FORCEPROP 1 LAST MATERIAL EMPTY
J 0
(-2460 3200);
DISPLAY 0.617021 (-2460 3200);
PAINT RED (-2460 3200);
FORCEPROP 1 LAST PART_NUMBER G21497-016
J 0
(-2460 3250);
DISPLAY 0.617021 (-2460 3250);
PAINT BLUE (-2460 3250);
FORCEPROP 2 LAST REUSE_ID 29
J 0
(-2525 3500);
DISPLAY 1.042553 (-2525 3500);
PAINT ORANGE (-2525 3500);
DISPLAY INVISIBLE (-2525 3500);
FORCEPROP 2 LAST CDS_SEC 1
J 0
(-2525 3500);
DISPLAY 1.042553 (-2525 3500);
PAINT ORANGE (-2525 3500);
DISPLAY INVISIBLE (-2525 3500);
FORCEPROP 2 LAST $SEC 1
J 0
(-2525 3500);
DISPLAY 0.680851 (-2525 3500);
PAINT MONO (-2525 3500);
DISPLAY INVISIBLE (-2525 3500);
FORCEPROP 2 LAST BOM_COST PVPP_KLM_VR
J 0
(-2525 3450);
DISPLAY 1.042553 (-2525 3450);
PAINT WHITE (-2525 3450);
DISPLAY INVISIBLE (-2525 3450);
FORCEPROP 1 LAST PATH I162
J 0
(-2525 3450);
DISPLAY 0.978723 (-2525 3450);
PAINT WHITE (-2525 3450);
DISPLAY INVISIBLE (-2525 3450);
FORCEPROP 2 LAST ROOM PVPP_KLM_VR
J 0
(-2525 3425);
PAINT GREEN (-2525 3425);
DISPLAY INVISIBLE (-2525 3425);
FORCEPROP 2 LAST CDS_LOCATION R4A7
J 0
(-2530 3375);
DISPLAY 0.617021 (-2530 3375);
PAINT AQUA (-2530 3375);
DISPLAY INVISIBLE (-2530 3375);
FORCEPROP 2 LAST CDS_LIB mstr_discrete
J 0
(-2575 3275);
PAINT MONO (-2575 3275);
DISPLAY INVISIBLE (-2575 3275);
FORCEADD CAP..1
(-2575 3600);
FORCEPROP 1 LAST PART_NUMBER A36096-091
J 0
(-2450 3525);
DISPLAY 0.617021 (-2450 3525);
PAINT BLUE (-2450 3525);
FORCEPROP 1 LAST MATERIAL EMPTY
J 0
(-2300 3575);
DISPLAY 0.617021 (-2300 3575);
PAINT RED (-2300 3575);
FORCEPROP 1 LAST TOLERANCE 10%
J 0
(-2350 3625);
DISPLAY 0.617021 (-2350 3625);
PAINT SKYBLUE (-2350 3625);
FORCEPROP 1 LAST VALUE 3300PF
J 0
(-2325 3675);
DISPLAY 0.617021 (-2325 3675);
PAINT SKYBLUE (-2325 3675);
FORCEPROP 1 LAST PACK_TYPE 0402LF
J 0
(-2450 3575);
DISPLAY 0.617021 (-2450 3575);
PAINT SKYBLUE (-2450 3575);
FORCEPROP 1 LAST VOLTAGE 50V
J 0
(-2450 3625);
DISPLAY 0.617021 (-2450 3625);
PAINT SKYBLUE (-2450 3625);
FORCEPROP 1 LAST LOCATION C4A16
J 0
(-2475 3675);
DISPLAY 0.617021 (-2475 3675);
PAINT AQUA (-2475 3675);
FORCEPROP 1 LASTPIN (-2575 3700) $PN 1
J 0
(-2565 3680);
DISPLAY 0.617021 (-2565 3680);
PAINT WHITE (-2565 3680);
FORCEPROP 1 LASTPIN (-2575 3500) $PN 2
J 0
(-2565 3480);
DISPLAY 0.617021 (-2565 3480);
PAINT WHITE (-2565 3480);
FORCEPROP 2 LAST CDS_LOCATION C4A16
J 0
(-2475 3700);
DISPLAY 0.617021 (-2475 3700);
PAINT AQUA (-2475 3700);
DISPLAY INVISIBLE (-2475 3700);
FORCEPROP 2 LAST REUSE_ID 26
J 0
(-2525 3800);
DISPLAY 1.042553 (-2525 3800);
PAINT ORANGE (-2525 3800);
DISPLAY INVISIBLE (-2525 3800);
FORCEPROP 2 LAST BOM_COST PVPP_KLM_VR
J 0
(-2525 3750);
DISPLAY 1.042553 (-2525 3750);
PAINT WHITE (-2525 3750);
DISPLAY INVISIBLE (-2525 3750);
FORCEPROP 2 LAST CDS_SEC 1
J 0
(-2525 3800);
DISPLAY 1.042553 (-2525 3800);
PAINT ORANGE (-2525 3800);
DISPLAY INVISIBLE (-2525 3800);
FORCEPROP 2 LAST $SEC 1
J 0
(-2525 3800);
DISPLAY 0.680851 (-2525 3800);
PAINT MONO (-2525 3800);
DISPLAY INVISIBLE (-2525 3800);
FORCEPROP 1 LAST PATH I163
J 0
(-2525 3750);
DISPLAY 0.978723 (-2525 3750);
PAINT WHITE (-2525 3750);
DISPLAY INVISIBLE (-2525 3750);
FORCEPROP 2 LAST ROOM PVPP_KLM_VR
J 0
(-2525 3725);
PAINT GREEN (-2525 3725);
DISPLAY INVISIBLE (-2525 3725);
FORCEPROP 2 LAST CDS_LIB mstr_discrete
J 0
(-2575 3600);
PAINT MONO (-2575 3600);
DISPLAY INVISIBLE (-2575 3600);
FORCEADD INDUCTOR..1
(-2300 3850);
FORCEPROP 1 LAST PACK_TYPE SM
J 0
(-2310 3790);
DISPLAY 0.617021 (-2310 3790);
PAINT SKYBLUE (-2310 3790);
FORCEPROP 1 LAST PART_NUMBER E13358-018
J 0
(-2275 3900);
DISPLAY 0.617021 (-2275 3900);
PAINT BLUE (-2275 3900);
FORCEPROP 1 LAST LOCATION L4A1
J 0
(-2450 3900);
DISPLAY 0.617021 (-2450 3900);
PAINT AQUA (-2450 3900);
FORCEPROP 1 LAST VALUE 0.47UH
J 2
(-2330 3790);
DISPLAY 0.617021 (-2330 3790);
PAINT SKYBLUE (-2330 3790);
FORCEPROP 1 LAST MATERIAL IND
J 0
(-2235 3790);
DISPLAY 0.617021 (-2235 3790);
PAINT SKYBLUE (-2235 3790);
FORCEPROP 1 LASTPIN (-2200 3850) $PN 2
J 2
(-2190 3860);
DISPLAY 0.617021 (-2190 3860);
PAINT WHITE (-2190 3860);
FORCEPROP 1 LASTPIN (-2400 3850) $PN 1
J 0
(-2400 3860);
DISPLAY 0.617021 (-2400 3860);
PAINT WHITE (-2400 3860);
FORCEPROP 2 LAST ROOM PVPP_KLM_VR
J 2
(-2300 3850);
PAINT GREEN (-2300 3850);
DISPLAY INVISIBLE (-2300 3850);
FORCEPROP 2 LAST CDS_LIB mstr_discrete
J 0
(-2300 3850);
PAINT MONO (-2300 3850);
DISPLAY INVISIBLE (-2300 3850);
FORCEPROP 2 LAST BOM_COST PVPP_KLM_VR
J 0
(-2300 3850);
PAINT WHITE (-2300 3850);
DISPLAY INVISIBLE (-2300 3850);
FORCEPROP 2 LAST REUSE_ID 30
J 0
(-2400 4050);
DISPLAY 1.042553 (-2400 4050);
PAINT ORANGE (-2400 4050);
DISPLAY INVISIBLE (-2400 4050);
FORCEPROP 0 LAST TOLERANCE 1%
J 0
(-2400 4000);
PAINT SKYBLUE (-2400 4000);
DISPLAY INVISIBLE (-2400 4000);
FORCEPROP 2 LAST CDS_SEC 1
J 0
(-2400 4050);
DISPLAY 1.042553 (-2400 4050);
PAINT ORANGE (-2400 4050);
DISPLAY INVISIBLE (-2400 4050);
FORCEPROP 2 LAST $SEC 1
J 0
(-2400 4050);
DISPLAY 0.680851 (-2400 4050);
PAINT MONO (-2400 4050);
DISPLAY INVISIBLE (-2400 4050);
FORCEPROP 2 LAST CDS_LOCATION L4A1
J 0
(-2350 3900);
DISPLAY 0.617021 (-2350 3900);
PAINT AQUA (-2350 3900);
DISPLAY INVISIBLE (-2350 3900);
FORCEPROP 1 LAST PATH I164
J 0
(-2400 4000);
DISPLAY 0.978723 (-2400 4000);
PAINT ORANGE (-2400 4000);
DISPLAY INVISIBLE (-2400 4000);
FORCEADD GND..1
(-2050 3400);
FORCEPROP 3 LASTPIN (-2050 3450) SIG_NAME GND\g
J 0
(-2040 3460);
DISPLAY 0.659574 (-2040 3460);
PAINT MONO (-2040 3460);
DISPLAY INVISIBLE (-2040 3460);
FORCEPROP 2 LAST BOM_COST PVPP_KLM_VR
J 0
(-2900 3475);
DISPLAY 1.042553 (-2900 3475);
PAINT WHITE (-2900 3475);
DISPLAY INVISIBLE (-2900 3475);
FORCEPROP 2 LAST ROOM PVPP_KLM_VR
J 0
(-2625 3475);
DISPLAY 1.042553 (-2625 3475);
PAINT GREEN (-2625 3475);
DISPLAY INVISIBLE (-2625 3475);
FORCEPROP 1 LAST BODY_TYPE PLUMBING
J 0
(-2095 3357);
DISPLAY 0.340426 (-2095 3357);
PAINT GREEN (-2095 3357);
DISPLAY INVISIBLE (-2095 3357);
FORCEPROP 2 LAST CDS_LIB mstr_symbols
J 0
(-2050 3400);
PAINT MONO (-2050 3400);
DISPLAY INVISIBLE (-2050 3400);
FORCEPROP 1 LAST VOLTAGE 0
J 0
(-2050 3400);
PAINT SKYBLUE (-2050 3400);
DISPLAY INVISIBLE (-2050 3400);
FORCEPROP 1 LAST HDL_POWER GND
J 0
(-2050 3550);
DISPLAY 0.872340 (-2050 3550);
PAINT GREEN (-2050 3550);
DISPLAY INVISIBLE (-2050 3550);
FORCEPROP 1 LAST PATH I165
J 0
(-1975 3400);
DISPLAY 0.872340 (-1975 3400);
PAINT AQUA (-1975 3400);
DISPLAY INVISIBLE (-1975 3400);
FORCEPROP 1 LAST SIZE 1B
J 0
(-1975 3350);
DISPLAY 0.872340 (-1975 3350);
PAINT GREEN (-1975 3350);
DISPLAY INVISIBLE (-1975 3350);
FORCEADD GND..1
(-1750 3350);
FORCEPROP 3 LASTPIN (-1750 3400) SIG_NAME GND\g
J 0
(-1740 3410);
DISPLAY 0.659574 (-1740 3410);
PAINT MONO (-1740 3410);
DISPLAY INVISIBLE (-1740 3410);
FORCEPROP 1 LAST HDL_POWER GND
J 0
(-1750 3500);
DISPLAY 0.872340 (-1750 3500);
PAINT GREEN (-1750 3500);
DISPLAY INVISIBLE (-1750 3500);
FORCEPROP 1 LAST PATH I166
J 0
(-1675 3350);
DISPLAY 0.872340 (-1675 3350);
PAINT AQUA (-1675 3350);
DISPLAY INVISIBLE (-1675 3350);
FORCEPROP 1 LAST SIZE 1B
J 0
(-1675 3300);
DISPLAY 0.872340 (-1675 3300);
PAINT GREEN (-1675 3300);
DISPLAY INVISIBLE (-1675 3300);
FORCEPROP 2 LAST CDS_LIB mstr_symbols
J 0
(-1750 3350);
PAINT MONO (-1750 3350);
DISPLAY INVISIBLE (-1750 3350);
FORCEPROP 1 LAST VOLTAGE 0
J 0
(-1750 3350);
PAINT SKYBLUE (-1750 3350);
DISPLAY INVISIBLE (-1750 3350);
FORCEPROP 1 LAST BODY_TYPE PLUMBING
J 0
(-1795 3307);
DISPLAY 0.340426 (-1795 3307);
PAINT GREEN (-1795 3307);
DISPLAY INVISIBLE (-1795 3307);
FORCEPROP 2 LAST ROOM PVPP_KLM_VR
J 0
(-2325 3425);
DISPLAY 1.042553 (-2325 3425);
PAINT GREEN (-2325 3425);
DISPLAY INVISIBLE (-2325 3425);
FORCEPROP 2 LAST BOM_COST PVPP_KLM_VR
J 0
(-2600 3425);
DISPLAY 1.042553 (-2600 3425);
PAINT WHITE (-2600 3425);
DISPLAY INVISIBLE (-2600 3425);
FORCEADD CAPP..1
(-1750 3650);
FORCEPROP 1 LAST PACK_TYPE 7343LF
J 0
(-1700 3550);
DISPLAY 0.617021 (-1700 3550);
PAINT SKYBLUE (-1700 3550);
FORCEPROP 1 LAST MATERIAL POSCAP
J 0
(-1700 3600);
DISPLAY 0.617021 (-1700 3600);
PAINT SKYBLUE (-1700 3600);
FORCEPROP 1 LAST VOLTAGE 6.3V
J 0
(-1700 3650);
DISPLAY 0.617021 (-1700 3650);
PAINT SKYBLUE (-1700 3650);
FORCEPROP 1 LAST TOLERANCE 20%
J 0
(-1700 3700);
DISPLAY 0.617021 (-1700 3700);
PAINT SKYBLUE (-1700 3700);
FORCEPROP 1 LAST VALUE 330UF
J 0
(-1700 3750);
DISPLAY 0.617021 (-1700 3750);
PAINT SKYBLUE (-1700 3750);
FORCEPROP 1 LAST LOCATION C3B3
J 0
(-1700 3800);
DISPLAY 0.617021 (-1700 3800);
PAINT AQUA (-1700 3800);
FORCEPROP 1 LASTPIN (-1750 3750) $PN 1
J 0
(-1740 3735);
DISPLAY 0.617021 (-1740 3735);
PAINT WHITE (-1740 3735);
FORCEPROP 1 LASTPIN (-1750 3550) $PN 2
J 0
(-1740 3535);
DISPLAY 0.617021 (-1740 3535);
PAINT WHITE (-1740 3535);
FORCEPROP 1 LAST PART_NUMBER 724613-042
J 0
(-1700 3500);
DISPLAY 0.617021 (-1700 3500);
PAINT BLUE (-1700 3500);
FORCEPROP 0 LAST GROUP PWR_BULK_CAP
J 0
(-1685 3451);
DISPLAY 0.638298 (-1685 3451);
PAINT BROWN (-1685 3451);
DISPLAY BOTH (-1685 3451);
FORCEPROP 2 LAST REUSE_ID 28
J 0
(-1700 3850);
DISPLAY 1.042553 (-1700 3850);
PAINT ORANGE (-1700 3850);
DISPLAY INVISIBLE (-1700 3850);
FORCEPROP 2 LAST CDS_SEC 1
J 0
(-1700 3850);
DISPLAY 1.042553 (-1700 3850);
PAINT ORANGE (-1700 3850);
DISPLAY INVISIBLE (-1700 3850);
FORCEPROP 2 LAST $SEC 1
J 0
(-1700 3850);
DISPLAY 0.680851 (-1700 3850);
PAINT MONO (-1700 3850);
DISPLAY INVISIBLE (-1700 3850);
FORCEPROP 1 LAST PATH I167
J 0
(-1700 3800);
DISPLAY 0.978723 (-1700 3800);
PAINT ORANGE (-1700 3800);
DISPLAY INVISIBLE (-1700 3800);
FORCEPROP 2 LAST CDS_LOCATION C3B3
J 0
(-1700 3750);
DISPLAY 0.617021 (-1700 3750);
PAINT AQUA (-1700 3750);
DISPLAY INVISIBLE (-1700 3750);
FORCEPROP 2 LAST CDS_LIB mstr_discrete
J 0
(-1750 3650);
PAINT MONO (-1750 3650);
DISPLAY INVISIBLE (-1750 3650);
FORCEPROP 2 LAST ROOM PVPP_KLM_VR
J 0
(-1750 3650);
PAINT GREEN (-1750 3650);
DISPLAY INVISIBLE (-1750 3650);
FORCEPROP 2 LAST BOM_COST PVPP_KLM_VR
J 0
(-1750 3650);
DISPLAY 0.659574 (-1750 3650);
PAINT WHITE (-1750 3650);
DISPLAY INVISIBLE (-1750 3650);
FORCEADD GND..1
(-1450 3350);
FORCEPROP 3 LASTPIN (-1450 3400) SIG_NAME GND\g
J 0
(-1440 3410);
DISPLAY 0.659574 (-1440 3410);
PAINT MONO (-1440 3410);
DISPLAY INVISIBLE (-1440 3410);
FORCEPROP 1 LAST HDL_POWER GND
J 0
(-1450 3500);
DISPLAY 0.872340 (-1450 3500);
PAINT GREEN (-1450 3500);
DISPLAY INVISIBLE (-1450 3500);
FORCEPROP 1 LAST SIZE 1B
J 0
(-1375 3300);
DISPLAY 0.872340 (-1375 3300);
PAINT GREEN (-1375 3300);
DISPLAY INVISIBLE (-1375 3300);
FORCEPROP 1 LAST PATH I175
J 0
(-1375 3350);
DISPLAY 0.872340 (-1375 3350);
PAINT AQUA (-1375 3350);
DISPLAY INVISIBLE (-1375 3350);
FORCEPROP 1 LAST VOLTAGE 0
J 0
(-1450 3350);
PAINT SKYBLUE (-1450 3350);
DISPLAY INVISIBLE (-1450 3350);
FORCEPROP 2 LAST CDS_LIB mstr_symbols
J 0
(-1450 3350);
PAINT MONO (-1450 3350);
DISPLAY INVISIBLE (-1450 3350);
FORCEPROP 1 LAST BODY_TYPE PLUMBING
J 0
(-1495 3307);
DISPLAY 0.340426 (-1495 3307);
PAINT GREEN (-1495 3307);
DISPLAY INVISIBLE (-1495 3307);
FORCEPROP 2 LAST ROOM PVPP_KLM_VR
J 0
(-2025 3425);
DISPLAY 1.042553 (-2025 3425);
PAINT GREEN (-2025 3425);
DISPLAY INVISIBLE (-2025 3425);
FORCEPROP 2 LAST BOM_COST PVPP_KLM_VR
J 0
(-2300 3425);
DISPLAY 1.042553 (-2300 3425);
PAINT WHITE (-2300 3425);
DISPLAY INVISIBLE (-2300 3425);
FORCEADD CAP..1
(-1150 3700);
FORCEPROP 1 LAST PACK_TYPE 0805
J 0
(-1100 3500);
DISPLAY 0.617021 (-1100 3500);
PAINT SKYBLUE (-1100 3500);
FORCEPROP 1 LASTPIN (-1150 3600) $PN 2
J 0
(-1140 3580);
DISPLAY 0.617021 (-1140 3580);
PAINT WHITE (-1140 3580);
FORCEPROP 1 LAST MATERIAL X6S
J 0
(-1100 3600);
DISPLAY 0.617021 (-1100 3600);
PAINT SKYBLUE (-1100 3600);
FORCEPROP 1 LAST PART_NUMBER C95333-006
J 0
(-1100 3550);
DISPLAY 0.617021 (-1100 3550);
PAINT BLUE (-1100 3550);
FORCEPROP 1 LASTPIN (-1150 3800) $PN 1
J 0
(-1140 3780);
DISPLAY 0.617021 (-1140 3780);
PAINT WHITE (-1140 3780);
FORCEPROP 1 LAST LOCATION C4B3
J 0
(-1100 3800);
DISPLAY 0.617021 (-1100 3800);
PAINT AQUA (-1100 3800);
FORCEPROP 1 LAST VALUE 47UF
J 0
(-1100 3750);
DISPLAY 0.617021 (-1100 3750);
PAINT SKYBLUE (-1100 3750);
FORCEPROP 1 LAST VOLTAGE 4V
J 0
(-1100 3700);
DISPLAY 0.617021 (-1100 3700);
PAINT SKYBLUE (-1100 3700);
FORCEPROP 1 LAST TOLERANCE 20%
J 0
(-1100 3650);
DISPLAY 0.617021 (-1100 3650);
PAINT SKYBLUE (-1100 3650);
FORCEPROP 0 LAST GROUP PWR_MLCC_CAP
J 0
(-1094 3437);
DISPLAY 0.638298 (-1094 3437);
PAINT BROWN (-1094 3437);
DISPLAY BOTH (-1094 3437);
FORCEPROP 2 LAST CDS_LIB mstr_discrete
J 0
(-1150 3700);
PAINT MONO (-1150 3700);
DISPLAY INVISIBLE (-1150 3700);
FORCEPROP 2 LAST BOM_COST PVPP_KLM_VR
J 0
(-1150 3700);
PAINT WHITE (-1150 3700);
DISPLAY INVISIBLE (-1150 3700);
FORCEPROP 2 LAST CDS_LOCATION C4B3
J 0
(-1100 3800);
DISPLAY 0.617021 (-1100 3800);
PAINT AQUA (-1100 3800);
DISPLAY INVISIBLE (-1100 3800);
FORCEPROP 2 LAST ROOM PVPP_KLM_VR
J 0
(-1150 3700);
PAINT GREEN (-1150 3700);
DISPLAY INVISIBLE (-1150 3700);
FORCEPROP 1 LAST PATH I177
J 0
(-1100 3850);
DISPLAY 0.978723 (-1100 3850);
PAINT WHITE (-1100 3850);
DISPLAY INVISIBLE (-1100 3850);
FORCEPROP 2 LAST REUSE_ID 33
J 0
(-1100 3900);
DISPLAY 1.042553 (-1100 3900);
PAINT ORANGE (-1100 3900);
DISPLAY INVISIBLE (-1100 3900);
FORCEPROP 2 LAST CDS_SEC 1
J 0
(-1100 3900);
DISPLAY 1.042553 (-1100 3900);
PAINT ORANGE (-1100 3900);
DISPLAY INVISIBLE (-1100 3900);
FORCEPROP 2 LAST $SEC 1
J 0
(-1100 3900);
DISPLAY 0.680851 (-1100 3900);
PAINT MONO (-1100 3900);
DISPLAY INVISIBLE (-1100 3900);
FORCEADD GND..1
(-1150 3350);
FORCEPROP 3 LASTPIN (-1150 3400) SIG_NAME GND\g
J 0
(-1140 3410);
DISPLAY 0.659574 (-1140 3410);
PAINT MONO (-1140 3410);
DISPLAY INVISIBLE (-1140 3410);
FORCEPROP 2 LAST ROOM PVPP_KLM_VR
J 0
(-1725 3425);
DISPLAY 1.042553 (-1725 3425);
PAINT GREEN (-1725 3425);
DISPLAY INVISIBLE (-1725 3425);
FORCEPROP 2 LAST BOM_COST PVPP_KLM_VR
J 0
(-2000 3425);
DISPLAY 1.042553 (-2000 3425);
PAINT WHITE (-2000 3425);
DISPLAY INVISIBLE (-2000 3425);
FORCEPROP 1 LAST BODY_TYPE PLUMBING
J 0
(-1195 3307);
DISPLAY 0.340426 (-1195 3307);
PAINT GREEN (-1195 3307);
DISPLAY INVISIBLE (-1195 3307);
FORCEPROP 1 LAST PATH I178
J 0
(-1075 3350);
DISPLAY 0.872340 (-1075 3350);
PAINT AQUA (-1075 3350);
DISPLAY INVISIBLE (-1075 3350);
FORCEPROP 1 LAST SIZE 1B
J 0
(-1075 3300);
DISPLAY 0.872340 (-1075 3300);
PAINT GREEN (-1075 3300);
DISPLAY INVISIBLE (-1075 3300);
FORCEPROP 2 LAST CDS_LIB mstr_symbols
J 0
(-1150 3350);
PAINT MONO (-1150 3350);
DISPLAY INVISIBLE (-1150 3350);
FORCEPROP 1 LAST VOLTAGE 0
J 0
(-1150 3350);
PAINT SKYBLUE (-1150 3350);
DISPLAY INVISIBLE (-1150 3350);
FORCEPROP 1 LAST HDL_POWER GND
J 0
(-1150 3500);
DISPLAY 0.872340 (-1150 3500);
PAINT GREEN (-1150 3500);
DISPLAY INVISIBLE (-1150 3500);
FORCEADD GND..1
(-850 3350);
FORCEPROP 3 LASTPIN (-850 3400) SIG_NAME GND\g
J 0
(-840 3410);
DISPLAY 0.659574 (-840 3410);
PAINT MONO (-840 3410);
DISPLAY INVISIBLE (-840 3410);
FORCEPROP 1 LAST HDL_POWER GND
J 0
(-850 3500);
DISPLAY 0.872340 (-850 3500);
PAINT GREEN (-850 3500);
DISPLAY INVISIBLE (-850 3500);
FORCEPROP 1 LAST PATH I179
J 0
(-775 3350);
DISPLAY 0.872340 (-775 3350);
PAINT AQUA (-775 3350);
DISPLAY INVISIBLE (-775 3350);
FORCEPROP 1 LAST VOLTAGE 0
J 0
(-850 3350);
PAINT SKYBLUE (-850 3350);
DISPLAY INVISIBLE (-850 3350);
FORCEPROP 2 LAST CDS_LIB mstr_symbols
J 0
(-850 3350);
PAINT MONO (-850 3350);
DISPLAY INVISIBLE (-850 3350);
FORCEPROP 1 LAST BODY_TYPE PLUMBING
J 0
(-895 3307);
DISPLAY 0.340426 (-895 3307);
PAINT GREEN (-895 3307);
DISPLAY INVISIBLE (-895 3307);
FORCEPROP 1 LAST SIZE 1B
J 0
(-775 3300);
DISPLAY 0.872340 (-775 3300);
PAINT GREEN (-775 3300);
DISPLAY INVISIBLE (-775 3300);
FORCEPROP 2 LAST ROOM PVPP_KLM_VR
J 0
(-1425 3425);
DISPLAY 1.042553 (-1425 3425);
PAINT GREEN (-1425 3425);
DISPLAY INVISIBLE (-1425 3425);
FORCEPROP 2 LAST BOM_COST PVPP_KLM_VR
J 0
(-1700 3425);
DISPLAY 1.042553 (-1700 3425);
PAINT WHITE (-1700 3425);
DISPLAY INVISIBLE (-1700 3425);
FORCEADD CAP..1
(-850 3700);
FORCEPROP 1 LASTPIN (-850 3600) $PN 2
J 0
(-840 3580);
DISPLAY 0.617021 (-840 3580);
PAINT WHITE (-840 3580);
FORCEPROP 1 LAST MATERIAL X6S
J 0
(-800 3600);
DISPLAY 0.617021 (-800 3600);
PAINT SKYBLUE (-800 3600);
FORCEPROP 1 LAST PACK_TYPE 0805
J 0
(-800 3500);
DISPLAY 0.617021 (-800 3500);
PAINT SKYBLUE (-800 3500);
FORCEPROP 1 LASTPIN (-850 3800) $PN 1
J 0
(-840 3780);
DISPLAY 0.617021 (-840 3780);
PAINT WHITE (-840 3780);
FORCEPROP 1 LAST TOLERANCE 20%
J 0
(-800 3650);
DISPLAY 0.617021 (-800 3650);
PAINT SKYBLUE (-800 3650);
FORCEPROP 1 LAST VALUE 47UF
J 0
(-800 3750);
DISPLAY 0.617021 (-800 3750);
PAINT SKYBLUE (-800 3750);
FORCEPROP 1 LAST LOCATION C4B2
J 0
(-800 3800);
DISPLAY 0.617021 (-800 3800);
PAINT AQUA (-800 3800);
FORCEPROP 1 LAST PART_NUMBER C95333-006
J 0
(-800 3550);
DISPLAY 0.617021 (-800 3550);
PAINT BLUE (-800 3550);
FORCEPROP 1 LAST VOLTAGE 4V
J 0
(-800 3700);
DISPLAY 0.617021 (-800 3700);
PAINT SKYBLUE (-800 3700);
FORCEPROP 0 LAST GROUP PWR_MLCC_CAP
J 0
(-794 3387);
DISPLAY 0.638298 (-794 3387);
PAINT BROWN (-794 3387);
DISPLAY BOTH (-794 3387);
FORCEPROP 2 LAST ROOM PVPP_KLM_VR
J 0
(-850 3700);
PAINT GREEN (-850 3700);
DISPLAY INVISIBLE (-850 3700);
FORCEPROP 2 LAST CDS_LOCATION C4B2
J 0
(-800 3800);
DISPLAY 0.617021 (-800 3800);
PAINT AQUA (-800 3800);
DISPLAY INVISIBLE (-800 3800);
FORCEPROP 2 LAST BOM_COST PVPP_KLM_VR
J 0
(-850 3700);
PAINT WHITE (-850 3700);
DISPLAY INVISIBLE (-850 3700);
FORCEPROP 2 LAST CDS_LIB mstr_discrete
J 0
(-850 3700);
PAINT MONO (-850 3700);
DISPLAY INVISIBLE (-850 3700);
FORCEPROP 1 LAST PATH I180
J 0
(-800 3850);
DISPLAY 0.978723 (-800 3850);
PAINT WHITE (-800 3850);
DISPLAY INVISIBLE (-800 3850);
FORCEPROP 2 LAST REUSE_ID 33
J 0
(-800 3900);
DISPLAY 1.042553 (-800 3900);
PAINT ORANGE (-800 3900);
DISPLAY INVISIBLE (-800 3900);
FORCEPROP 2 LAST CDS_SEC 1
J 0
(-800 3900);
DISPLAY 1.042553 (-800 3900);
PAINT ORANGE (-800 3900);
DISPLAY INVISIBLE (-800 3900);
FORCEPROP 2 LAST $SEC 1
J 0
(-800 3900);
DISPLAY 0.680851 (-800 3900);
PAINT MONO (-800 3900);
DISPLAY INVISIBLE (-800 3900);
FORCEADD CAP..2
R 2
(-3375 4200);
FORCEPROP 1 LAST TOLERANCE 10%
J 0
(-3375 4050);
DISPLAY 0.617021 (-3375 4050);
PAINT SKYBLUE (-3375 4050);
FORCEPROP 1 LAST PACK_TYPE 0603LF
J 1
(-3375 4000);
DISPLAY 0.617021 (-3375 4000);
PAINT SKYBLUE (-3375 4000);
FORCEPROP 1 LASTPIN (-3275 4200) $PN 1
J 2
(-3265 4215);
DISPLAY 0.617021 (-3265 4215);
PAINT WHITE (-3265 4215);
FORCEPROP 1 LAST PART_NUMBER 602433-020
J 1
(-3375 4250);
DISPLAY 0.617021 (-3375 4250);
PAINT BLUE (-3375 4250);
FORCEPROP 1 LAST VOLTAGE 25V
J 2
(-3375 4100);
DISPLAY 0.617021 (-3375 4100);
PAINT SKYBLUE (-3375 4100);
FORCEPROP 1 LASTPIN (-3475 4200) $PN 2
J 2
(-3460 4215);
DISPLAY 0.617021 (-3460 4215);
PAINT WHITE (-3460 4215);
FORCEPROP 1 LAST MATERIAL X7R
J 2
(-3375 4050);
DISPLAY 0.617021 (-3375 4050);
PAINT SKYBLUE (-3375 4050);
FORCEPROP 1 LAST VALUE 0.1UF
J 0
(-3375 4100);
DISPLAY 0.617021 (-3375 4100);
PAINT SKYBLUE (-3375 4100);
FORCEPROP 1 LAST LOCATION C4B15
J 1
(-3375 4300);
DISPLAY 0.617021 (-3375 4300);
PAINT AQUA (-3375 4300);
FORCEPROP 2 LAST $SEC 1
J 0
(-3375 4450);
DISPLAY 0.680851 (-3375 4450);
PAINT MONO (-3375 4450);
DISPLAY INVISIBLE (-3375 4450);
FORCEPROP 2 LAST CDS_SEC 1
J 0
(-3420 4410);
DISPLAY 1.042553 (-3420 4410);
PAINT ORANGE (-3420 4410);
DISPLAY INVISIBLE (-3420 4410);
FORCEPROP 2 LAST CDS_LIB mstr_discrete
J 0
(-3375 4200);
PAINT MONO (-3375 4200);
DISPLAY INVISIBLE (-3375 4200);
FORCEPROP 1 LAST PATH I182
J 2
(-3375 4400);
DISPLAY 0.978723 (-3375 4400);
PAINT WHITE (-3375 4400);
DISPLAY INVISIBLE (-3375 4400);
FORCEPROP 2 LAST ROOM PVPP_KLM_VR
J 2
(-3375 4325);
DISPLAY 0.765957 (-3375 4325);
PAINT GREEN (-3375 4325);
DISPLAY INVISIBLE (-3375 4325);
FORCEPROP 2 LAST REUSE_ID 27
J 0
(-3375 4450);
DISPLAY 1.042553 (-3375 4450);
PAINT ORANGE (-3375 4450);
DISPLAY INVISIBLE (-3375 4450);
FORCEPROP 2 LAST BOM_COST PVPP_KLM_VR
J 0
(-3420 4360);
DISPLAY 1.042553 (-3420 4360);
PAINT WHITE (-3420 4360);
DISPLAY INVISIBLE (-3420 4360);
FORCEADD RES..2
(-2050 3650);
FORCEPROP 1 LAST PART_NUMBER G22026-003
J 0
(-2010 3525);
DISPLAY 0.617021 (-2010 3525);
PAINT BLUE (-2010 3525);
FORCEPROP 1 LAST PACK_TYPE 0603
J 0
(-2010 3475);
DISPLAY 0.617021 (-2010 3475);
PAINT SKYBLUE (-2010 3475);
FORCEPROP 1 LAST LOCATION R4B2
J 0
(-2005 3775);
DISPLAY 0.617021 (-2005 3775);
PAINT AQUA (-2005 3775);
FORCEPROP 1 LAST VALUE 120.0
J 0
(-2005 3725);
DISPLAY 0.617021 (-2005 3725);
PAINT SKYBLUE (-2005 3725);
FORCEPROP 1 LAST TOLERANCE 1%
J 0
(-2005 3675);
DISPLAY 0.617021 (-2005 3675);
PAINT SKYBLUE (-2005 3675);
FORCEPROP 1 LAST WATTAGE 1/10W
J 0
(-2010 3625);
DISPLAY 0.617021 (-2010 3625);
PAINT SKYBLUE (-2010 3625);
FORCEPROP 1 LAST MATERIAL CHIP
J 0
(-2010 3575);
DISPLAY 0.617021 (-2010 3575);
PAINT SKYBLUE (-2010 3575);
FORCEPROP 1 LASTPIN (-2050 3750) $PN 1
J 0
(-2045 3712);
DISPLAY 0.617021 (-2045 3712);
PAINT WHITE (-2045 3712);
FORCEPROP 1 LASTPIN (-2050 3550) $PN 2
J 0
(-2045 3560);
DISPLAY 0.617021 (-2045 3560);
PAINT WHITE (-2045 3560);
FORCEPROP 2 LAST CDS_LIB mstr_discrete
J 0
(-2050 3650);
PAINT MONO (-2050 3650);
DISPLAY INVISIBLE (-2050 3650);
FORCEPROP 2 LAST ROOM PVPP_KLM_VR
J 0
(-2005 3805);
PAINT GREEN (-2005 3805);
DISPLAY INVISIBLE (-2005 3805);
FORCEPROP 1 LAST PATH I183
J 0
(-2000 3825);
DISPLAY 0.978723 (-2000 3825);
PAINT WHITE (-2000 3825);
DISPLAY INVISIBLE (-2000 3825);
FORCEPROP 2 LAST CDS_LOCATION R4B2
J 0
(-2005 3775);
DISPLAY 0.617021 (-2005 3775);
PAINT AQUA (-2005 3775);
DISPLAY INVISIBLE (-2005 3775);
FORCEPROP 2 LAST $SEC 1
J 0
(-2000 3875);
DISPLAY 0.680851 (-2000 3875);
PAINT MONO (-2000 3875);
DISPLAY INVISIBLE (-2000 3875);
FORCEPROP 2 LAST CDS_SEC 1
J 0
(-2000 3875);
DISPLAY 1.042553 (-2000 3875);
PAINT ORANGE (-2000 3875);
DISPLAY INVISIBLE (-2000 3875);
FORCEPROP 2 LAST BOM_COST PVPP_KLM_VR
J 0
(-2005 3830);
DISPLAY 1.042553 (-2005 3830);
PAINT WHITE (-2005 3830);
DISPLAY INVISIBLE (-2005 3830);
FORCEPROP 2 LAST REUSE_ID 34
J 0
(-2000 3875);
DISPLAY 1.042553 (-2000 3875);
PAINT ORANGE (-2000 3875);
DISPLAY INVISIBLE (-2000 3875);
FORCEADD NCP3232L..1
(-3800 2875);
FORCEPROP 2 LASTPIN (-3300 2225) $PN 19
J 0
(-3290 2235);
DISPLAY 0.617021 (-3290 2235);
PAINT ORANGE (-3290 2235);
FORCEPROP 1 LAST PART_NUMBER H86355-001
J 0
(-4250 1875);
DISPLAY 0.617021 (-4250 1875);
PAINT BLUE (-4250 1875);
FORCEPROP 2 LASTPIN (-3300 2275) $PN 20
J 0
(-3290 2285);
DISPLAY 0.617021 (-3290 2285);
PAINT ORANGE (-3290 2285);
FORCEPROP 2 LASTPIN (-3300 2725) $PN 37
J 0
(-3290 2735);
DISPLAY 0.617021 (-3290 2735);
PAINT ORANGE (-3290 2735);
FORCEPROP 2 LASTPIN (-3300 3575) $PN 36
J 0
(-3290 3585);
DISPLAY 0.617021 (-3290 3585);
PAINT ORANGE (-3290 3585);
FORCEPROP 2 LASTPIN (-3300 3475) $PN 43
J 0
(-3290 3485);
DISPLAY 0.617021 (-3290 3485);
PAINT ORANGE (-3290 3485);
FORCEPROP 2 LASTPIN (-3300 3325) $PN 32
J 0
(-3290 3335);
DISPLAY 0.617021 (-3290 3335);
PAINT ORANGE (-3290 3335);
FORCEPROP 2 LASTPIN (-3300 3375) $PN 33
J 0
(-3290 3385);
DISPLAY 0.617021 (-3290 3385);
PAINT ORANGE (-3290 3385);
FORCEPROP 2 LASTPIN (-3300 3425) $PN 34
J 0
(-3290 3435);
DISPLAY 0.617021 (-3290 3435);
PAINT ORANGE (-3290 3435);
FORCEPROP 2 LASTPIN (-3300 3225) $PN 30
J 0
(-3290 3235);
DISPLAY 0.617021 (-3290 3235);
PAINT ORANGE (-3290 3235);
FORCEPROP 2 LASTPIN (-3300 3275) $PN 31
J 0
(-3290 3285);
DISPLAY 0.617021 (-3290 3285);
PAINT ORANGE (-3290 3285);
FORCEPROP 2 LASTPIN (-3300 3125) $PN 15
J 0
(-3290 3135);
DISPLAY 0.617021 (-3290 3135);
PAINT ORANGE (-3290 3135);
FORCEPROP 2 LASTPIN (-3300 3175) $PN 29
J 0
(-3290 3185);
DISPLAY 0.617021 (-3290 3185);
PAINT ORANGE (-3290 3185);
FORCEPROP 2 LASTPIN (-3300 2825) $PN 3
J 0
(-3290 2835);
DISPLAY 0.617021 (-3290 2835);
PAINT ORANGE (-3290 2835);
FORCEPROP 2 LASTPIN (-3300 2925) $PN 2
J 0
(-3290 2935);
DISPLAY 0.617021 (-3290 2935);
PAINT ORANGE (-3290 2935);
FORCEPROP 2 LASTPIN (-3300 3025) $PN 35
J 0
(-3290 3035);
DISPLAY 0.617021 (-3290 3035);
PAINT ORANGE (-3290 3035);
FORCEPROP 2 LASTPIN (-3300 2575) $PN 26
J 0
(-3290 2585);
DISPLAY 0.617021 (-3290 2585);
PAINT ORANGE (-3290 2585);
FORCEPROP 2 LASTPIN (-3300 2625) $PN 27
J 0
(-3290 2635);
DISPLAY 0.617021 (-3290 2635);
PAINT ORANGE (-3290 2635);
FORCEPROP 2 LASTPIN (-3300 2675) $PN 28
J 0
(-3290 2685);
DISPLAY 0.617021 (-3290 2685);
PAINT ORANGE (-3290 2685);
FORCEPROP 2 LASTPIN (-3300 2525) $PN 25
J 0
(-3290 2535);
DISPLAY 0.617021 (-3290 2535);
PAINT ORANGE (-3290 2535);
FORCEPROP 2 LASTPIN (-3300 2375) $PN 22
J 0
(-3290 2385);
DISPLAY 0.617021 (-3290 2385);
PAINT ORANGE (-3290 2385);
FORCEPROP 2 LASTPIN (-3300 2425) $PN 23
J 0
(-3290 2435);
DISPLAY 0.617021 (-3290 2435);
PAINT ORANGE (-3290 2435);
FORCEPROP 2 LASTPIN (-3300 2475) $PN 24
J 0
(-3290 2485);
DISPLAY 0.617021 (-3290 2485);
PAINT ORANGE (-3290 2485);
FORCEPROP 2 LASTPIN (-3300 2325) $PN 21
J 0
(-3290 2335);
DISPLAY 0.617021 (-3290 2335);
PAINT ORANGE (-3290 2335);
FORCEPROP 2 LASTPIN (-3300 2125) $PN 17
J 0
(-3290 2135);
DISPLAY 0.617021 (-3290 2135);
PAINT ORANGE (-3290 2135);
FORCEPROP 2 LASTPIN (-3300 2175) $PN 18
J 0
(-3290 2185);
DISPLAY 0.617021 (-3290 2185);
PAINT ORANGE (-3290 2185);
FORCEPROP 2 LASTPIN (-3300 2075) $PN 16
J 0
(-3290 2085);
DISPLAY 0.617021 (-3290 2085);
PAINT ORANGE (-3290 2085);
FORCEPROP 2 LASTPIN (-3300 2025) $PN 41
J 0
(-3290 2035);
DISPLAY 0.617021 (-3290 2035);
PAINT ORANGE (-3290 2035);
FORCEPROP 1 LAST MATERIAL IC
J 0
(-4250 3775);
DISPLAY 0.617021 (-4250 3775);
PAINT SKYBLUE (-4250 3775);
FORCEPROP 2 LASTPIN (-4300 3575) $PN 39
J 2
(-4310 3585);
DISPLAY 0.617021 (-4310 3585);
PAINT ORANGE (-4310 3585);
FORCEPROP 2 LASTPIN (-4300 3175) $PN 9
J 2
(-4310 3185);
DISPLAY 0.617021 (-4310 3185);
PAINT ORANGE (-4310 3185);
FORCEPROP 2 LASTPIN (-4300 3125) $PN 8
J 2
(-4310 3135);
DISPLAY 0.617021 (-4310 3135);
PAINT ORANGE (-4310 3135);
FORCEPROP 2 LASTPIN (-4300 3475) $PN 42
J 2
(-4310 3485);
DISPLAY 0.617021 (-4310 3485);
PAINT ORANGE (-4310 3485);
FORCEPROP 2 LASTPIN (-4300 3425) $PN 14
J 2
(-4310 3435);
DISPLAY 0.617021 (-4310 3435);
PAINT ORANGE (-4310 3435);
FORCEPROP 2 LASTPIN (-4300 3375) $PN 13
J 2
(-4310 3385);
DISPLAY 0.617021 (-4310 3385);
PAINT ORANGE (-4310 3385);
FORCEPROP 2 LASTPIN (-4300 3325) $PN 12
J 2
(-4310 3335);
DISPLAY 0.617021 (-4310 3335);
PAINT ORANGE (-4310 3335);
FORCEPROP 2 LASTPIN (-4300 3275) $PN 11
J 2
(-4310 3285);
DISPLAY 0.617021 (-4310 3285);
PAINT ORANGE (-4310 3285);
FORCEPROP 2 LASTPIN (-4300 3225) $PN 10
J 2
(-4310 3235);
DISPLAY 0.617021 (-4310 3235);
PAINT ORANGE (-4310 3235);
FORCEPROP 2 LASTPIN (-4300 2925) $PN 6
J 2
(-4310 2935);
DISPLAY 0.617021 (-4310 2935);
PAINT ORANGE (-4310 2935);
FORCEPROP 2 LASTPIN (-4300 2625) $PN 4
J 2
(-4310 2635);
DISPLAY 0.617021 (-4310 2635);
PAINT ORANGE (-4310 2635);
FORCEPROP 2 LASTPIN (-4300 2725) $PN 1
J 2
(-4310 2735);
DISPLAY 0.617021 (-4310 2735);
PAINT ORANGE (-4310 2735);
FORCEPROP 2 LASTPIN (-4300 3025) $PN 38
J 2
(-4310 3035);
DISPLAY 0.617021 (-4310 3035);
PAINT ORANGE (-4310 3035);
FORCEPROP 2 LASTPIN (-4300 2825) $PN 40
J 2
(-4310 2835);
DISPLAY 0.617021 (-4310 2835);
PAINT ORANGE (-4310 2835);
FORCEPROP 2 LASTPIN (-4300 2525) $PN 7
J 2
(-4310 2535);
DISPLAY 0.617021 (-4310 2535);
PAINT ORANGE (-4310 2535);
FORCEPROP 2 LASTPIN (-4300 2025) $PN 5
J 2
(-4310 2035);
DISPLAY 0.617021 (-4310 2035);
PAINT ORANGE (-4310 2035);
FORCEPROP 1 LAST LOCATION EU4A3
J 0
(-4250 3825);
DISPLAY 0.617021 (-4250 3825);
PAINT AQUA (-4250 3825);
FORCEPROP 1 LAST PATH I184
J 0
(-3750 3775);
PAINT GREEN (-3750 3775);
DISPLAY INVISIBLE (-3750 3775);
FORCEPROP 1 LAST CDS_LMAN_SYM_OUTLINE -450,850,450,-900
J 0
(-3800 2875);
DISPLAY 0.468085 (-3800 2875);
PAINT GREEN (-3800 2875);
DISPLAY INVISIBLE (-3800 2875);
FORCEPROP 2 LAST CDS_LIB mstr_vreg
J 0
(-3800 2875);
PAINT ORANGE (-3800 2875);
DISPLAY INVISIBLE (-3800 2875);
FORCEPROP 1 LAST PACK_TYPE SM
J 0
(-4250 3875);
PAINT SKYBLUE (-4250 3875);
DISPLAY INVISIBLE (-4250 3875);
FORCEPROP 2 LAST SEC_TYPE SM
J 0
(-4250 3875);
DISPLAY 1.021277 (-4250 3875);
PAINT ORANGE (-4250 3875);
DISPLAY INVISIBLE (-4250 3875);
FORCEPROP 2 LAST SEC 1
J 0
(-4250 3875);
DISPLAY 0.680851 (-4250 3875);
PAINT MONO (-4250 3875);
DISPLAY INVISIBLE (-4250 3875);
FORCEPROP 2 LAST CDS_LOCATION EU4A3
J 0
(-4250 3825);
DISPLAY 0.617021 (-4250 3825);
PAINT AQUA (-4250 3825);
DISPLAY INVISIBLE (-4250 3825);
FORCEADD PVPP_KLM..1
(-800 3975);
FORCEPROP 3 LASTPIN (-800 3925) SIG_NAME PVPP_KLM\g
J 0
(-790 3935);
DISPLAY 0.659574 (-790 3935);
PAINT MONO (-790 3935);
DISPLAY INVISIBLE (-790 3935);
FORCEPROP 2 LAST BOM_COST PVPP_KLM_VR
J 0
(-725 4075);
PAINT MONO (-725 4075);
DISPLAY INVISIBLE (-725 4075);
FORCEPROP 2 LAST ROOM PVPP_KLM_VR
J 0
(-550 4075);
PAINT ORANGE (-550 4075);
DISPLAY INVISIBLE (-550 4075);
FORCEPROP 1 LAST PATH I185
J 0
(-750 4000);
DISPLAY 0.872340 (-750 4000);
PAINT AQUA (-750 4000);
DISPLAY INVISIBLE (-750 4000);
FORCEPROP 1 LAST HDL_POWER PVPP_KLM
J 1
(-800 4025);
DISPLAY 0.872340 (-800 4025);
PAINT GREEN (-800 4025);
DISPLAY INVISIBLE (-800 4025);
FORCEPROP 2 LAST CDS_LIB mstr_symbols
J 0
(-800 3975);
PAINT ORANGE (-800 3975);
DISPLAY INVISIBLE (-800 3975);
FORCEPROP 1 LAST BODY_TYPE PLUMBING
J 0
(-845 3932);
DISPLAY 0.340426 (-845 3932);
PAINT GREEN (-845 3932);
DISPLAY INVISIBLE (-845 3932);
FORCEPROP 1 LAST VOLTAGE 2.5V
J 0
(-845 3932);
DISPLAY 0.340426 (-845 3932);
PAINT SKYBLUE (-845 3932);
DISPLAY INVISIBLE (-845 3932);
FORCEADD AGND_SCSI..1
(-6300 2075);
FORCEPROP 3 LASTPIN (-6300 2125) SIG_NAME AGND_PVPP_KLM\g
J 0
(-6290 2135);
DISPLAY 0.659574 (-6290 2135);
PAINT MONO (-6290 2135);
DISPLAY INVISIBLE (-6290 2135);
FORCEPROP 1 LAST HDL_POWER AGND_PVPP_KLM
J 1
(-6225 2000);
DISPLAY 0.617021 (-6225 2000);
PAINT GREEN (-6225 2000);
FORCEPROP 1 LAST PATH I187
J 0
(-6225 2075);
DISPLAY 0.872340 (-6225 2075);
PAINT AQUA (-6225 2075);
DISPLAY INVISIBLE (-6225 2075);
FORCEPROP 2 LAST CDS_LIB mstr_symbols
J 0
(-6300 2075);
PAINT MONO (-6300 2075);
DISPLAY INVISIBLE (-6300 2075);
FORCEPROP 2 LAST BOM_COST PVPP_KLM_VR
J 0
(-6450 2025);
DISPLAY 1.042553 (-6450 2025);
PAINT WHITE (-6450 2025);
DISPLAY INVISIBLE (-6450 2025);
FORCEPROP 2 LAST ROOM PVPP_KLM_VR
J 0
(-6450 2025);
DISPLAY 1.042553 (-6450 2025);
PAINT GREEN (-6450 2025);
DISPLAY INVISIBLE (-6450 2025);
FORCEPROP 1 LAST VOLTAGE 0.0V
J 0
(-6345 2032);
DISPLAY 0.340426 (-6345 2032);
PAINT SKYBLUE (-6345 2032);
DISPLAY INVISIBLE (-6345 2032);
FORCEPROP 1 LAST BODY_TYPE PLUMBING
J 0
(-6345 2032);
DISPLAY 0.340426 (-6345 2032);
PAINT GREEN (-6345 2032);
DISPLAY INVISIBLE (-6345 2032);
FORCEADD AGND_SCSI..1
(-5650 2150);
FORCEPROP 3 LASTPIN (-5650 2200) SIG_NAME AGND_PVPP_KLM\g
J 0
(-5640 2210);
DISPLAY 0.659574 (-5640 2210);
PAINT MONO (-5640 2210);
DISPLAY INVISIBLE (-5640 2210);
FORCEPROP 1 LAST HDL_POWER AGND_PVPP_KLM
J 1
(-5575 2075);
DISPLAY 0.617021 (-5575 2075);
PAINT GREEN (-5575 2075);
FORCEPROP 2 LAST ROOM PVPP_KLM_VR
J 0
(-5800 2100);
DISPLAY 1.042553 (-5800 2100);
PAINT GREEN (-5800 2100);
DISPLAY INVISIBLE (-5800 2100);
FORCEPROP 1 LAST BODY_TYPE PLUMBING
J 0
(-5695 2107);
DISPLAY 0.340426 (-5695 2107);
PAINT GREEN (-5695 2107);
DISPLAY INVISIBLE (-5695 2107);
FORCEPROP 2 LAST BOM_COST PVPP_KLM_VR
J 0
(-5800 2100);
DISPLAY 1.042553 (-5800 2100);
PAINT WHITE (-5800 2100);
DISPLAY INVISIBLE (-5800 2100);
FORCEPROP 1 LAST VOLTAGE 0.0V
J 0
(-5695 2107);
DISPLAY 0.340426 (-5695 2107);
PAINT SKYBLUE (-5695 2107);
DISPLAY INVISIBLE (-5695 2107);
FORCEPROP 1 LAST PATH I188
J 0
(-5575 2150);
DISPLAY 0.872340 (-5575 2150);
PAINT AQUA (-5575 2150);
DISPLAY INVISIBLE (-5575 2150);
FORCEPROP 2 LAST CDS_LIB mstr_symbols
J 0
(-5650 2150);
PAINT MONO (-5650 2150);
DISPLAY INVISIBLE (-5650 2150);
FORCEADD AGND_SCSI..1
(-5075 1950);
FORCEPROP 3 LASTPIN (-5075 2000) SIG_NAME AGND_PVPP_KLM\g
J 0
(-5065 2010);
DISPLAY 0.659574 (-5065 2010);
PAINT MONO (-5065 2010);
DISPLAY INVISIBLE (-5065 2010);
FORCEPROP 1 LAST HDL_POWER AGND_PVPP_KLM
J 1
(-5000 1875);
DISPLAY 0.617021 (-5000 1875);
PAINT GREEN (-5000 1875);
FORCEPROP 2 LAST CDS_LIB mstr_symbols
J 0
(-5075 1950);
PAINT MONO (-5075 1950);
DISPLAY INVISIBLE (-5075 1950);
FORCEPROP 1 LAST PATH I189
J 0
(-5000 1950);
DISPLAY 0.872340 (-5000 1950);
PAINT AQUA (-5000 1950);
DISPLAY INVISIBLE (-5000 1950);
FORCEPROP 1 LAST VOLTAGE 0.0V
J 0
(-5120 1907);
DISPLAY 0.340426 (-5120 1907);
PAINT SKYBLUE (-5120 1907);
DISPLAY INVISIBLE (-5120 1907);
FORCEPROP 1 LAST BODY_TYPE PLUMBING
J 0
(-5120 1907);
DISPLAY 0.340426 (-5120 1907);
PAINT GREEN (-5120 1907);
DISPLAY INVISIBLE (-5120 1907);
FORCEPROP 2 LAST BOM_COST PVPP_KLM_VR
J 0
(-5225 1900);
DISPLAY 1.042553 (-5225 1900);
PAINT WHITE (-5225 1900);
DISPLAY INVISIBLE (-5225 1900);
FORCEPROP 2 LAST ROOM PVPP_KLM_VR
J 0
(-5225 1900);
DISPLAY 1.042553 (-5225 1900);
PAINT GREEN (-5225 1900);
DISPLAY INVISIBLE (-5225 1900);
FORCEADD AGND_SCSI..1
(-4750 1350);
FORCEPROP 3 LASTPIN (-4750 1400) SIG_NAME AGND_PVPP_KLM\g
J 0
(-4740 1410);
DISPLAY 0.659574 (-4740 1410);
PAINT MONO (-4740 1410);
DISPLAY INVISIBLE (-4740 1410);
FORCEPROP 1 LAST HDL_POWER AGND_PVPP_KLM
J 1
(-4750 1300);
DISPLAY 0.617021 (-4750 1300);
PAINT GREEN (-4750 1300);
FORCEPROP 1 LAST VOLTAGE 0
J 0
(-4675 1375);
DISPLAY 1.021277 (-4675 1375);
PAINT SKYBLUE (-4675 1375);
DISPLAY INVISIBLE (-4675 1375);
FORCEPROP 2 LAST CDS_LIB mstr_symbols
J 0
(-4750 1350);
PAINT MONO (-4750 1350);
DISPLAY INVISIBLE (-4750 1350);
FORCEPROP 1 LAST BODY_TYPE PLUMBING
J 0
(-4795 1307);
DISPLAY 0.340426 (-4795 1307);
PAINT GREEN (-4795 1307);
DISPLAY INVISIBLE (-4795 1307);
FORCEPROP 1 LAST PATH I190
J 0
(-4675 1350);
DISPLAY 0.872340 (-4675 1350);
PAINT AQUA (-4675 1350);
DISPLAY INVISIBLE (-4675 1350);
FORCEADD AGND_SCSI..1
(-4375 1850);
FORCEPROP 3 LASTPIN (-4375 1900) SIG_NAME AGND_PVPP_KLM\g
J 0
(-4365 1910);
DISPLAY 0.659574 (-4365 1910);
PAINT MONO (-4365 1910);
DISPLAY INVISIBLE (-4365 1910);
FORCEPROP 1 LAST HDL_POWER AGND_PVPP_KLM
J 1
(-4300 1775);
DISPLAY 0.617021 (-4300 1775);
PAINT GREEN (-4300 1775);
FORCEPROP 1 LAST PATH I191
J 0
(-4300 1850);
DISPLAY 0.872340 (-4300 1850);
PAINT AQUA (-4300 1850);
DISPLAY INVISIBLE (-4300 1850);
FORCEPROP 1 LAST BODY_TYPE PLUMBING
J 0
(-4420 1807);
DISPLAY 0.340426 (-4420 1807);
PAINT GREEN (-4420 1807);
DISPLAY INVISIBLE (-4420 1807);
FORCEPROP 2 LAST BOM_COST PVPP_KLM_VR
J 0
(-4525 1800);
DISPLAY 1.042553 (-4525 1800);
PAINT WHITE (-4525 1800);
DISPLAY INVISIBLE (-4525 1800);
FORCEPROP 2 LAST CDS_LIB mstr_symbols
J 0
(-4375 1850);
PAINT MONO (-4375 1850);
DISPLAY INVISIBLE (-4375 1850);
FORCEPROP 1 LAST VOLTAGE 0.0V
J 0
(-4420 1807);
DISPLAY 0.340426 (-4420 1807);
PAINT SKYBLUE (-4420 1807);
DISPLAY INVISIBLE (-4420 1807);
FORCEPROP 2 LAST ROOM PVPP_KLM_VR
J 0
(-4525 1800);
DISPLAY 1.042553 (-4525 1800);
PAINT GREEN (-4525 1800);
DISPLAY INVISIBLE (-4525 1800);
FORCEADD GND..1
(-5175 3300);
FORCEPROP 3 LASTPIN (-5175 3350) SIG_NAME GND\g
J 0
(-5165 3360);
DISPLAY 0.659574 (-5165 3360);
PAINT MONO (-5165 3360);
DISPLAY INVISIBLE (-5165 3360);
FORCEPROP 1 LAST PATH I198
J 0
(-5100 3300);
DISPLAY 0.872340 (-5100 3300);
PAINT AQUA (-5100 3300);
DISPLAY INVISIBLE (-5100 3300);
FORCEPROP 1 LAST SIZE 1B
J 0
(-5100 3250);
DISPLAY 0.872340 (-5100 3250);
PAINT GREEN (-5100 3250);
DISPLAY INVISIBLE (-5100 3250);
FORCEPROP 1 LAST HDL_POWER GND
J 0
(-5175 3450);
DISPLAY 0.872340 (-5175 3450);
PAINT GREEN (-5175 3450);
DISPLAY INVISIBLE (-5175 3450);
FORCEPROP 1 LAST VOLTAGE 0
J 0
(-5175 3300);
PAINT SKYBLUE (-5175 3300);
DISPLAY INVISIBLE (-5175 3300);
FORCEPROP 2 LAST CDS_LIB mstr_symbols
J 0
(-5175 3300);
PAINT MONO (-5175 3300);
DISPLAY INVISIBLE (-5175 3300);
FORCEPROP 1 LAST BODY_TYPE PLUMBING
J 0
(-5220 3257);
DISPLAY 0.340426 (-5220 3257);
PAINT GREEN (-5220 3257);
DISPLAY INVISIBLE (-5220 3257);
FORCEPROP 2 LAST BOM_COST PVPP_KLM_VR
J 0
(-6025 3375);
DISPLAY 1.042553 (-6025 3375);
PAINT WHITE (-6025 3375);
DISPLAY INVISIBLE (-6025 3375);
FORCEPROP 2 LAST ROOM PVPP_KLM_VR
J 0
(-5750 3375);
DISPLAY 1.042553 (-5750 3375);
PAINT GREEN (-5750 3375);
DISPLAY INVISIBLE (-5750 3375);
FORCEADD CAP_A..1
(-5175 3525);
FORCEPROP 1 LAST PACK_TYPE 0402V
J 0
(-5125 3325);
DISPLAY 0.617021 (-5125 3325);
PAINT SKYBLUE (-5125 3325);
FORCEPROP 1 LAST PART_NUMBER A36096-030
J 0
(-5125 3375);
DISPLAY 0.617021 (-5125 3375);
PAINT BLUE (-5125 3375);
FORCEPROP 1 LAST VALUE 0.1UF
J 0
(-5125 3575);
DISPLAY 0.617021 (-5125 3575);
PAINT SKYBLUE (-5125 3575);
FORCEPROP 1 LAST LOCATION C4A20
J 0
(-5125 3625);
DISPLAY 0.617021 (-5125 3625);
PAINT AQUA (-5125 3625);
FORCEPROP 1 LAST TOLERANCE 10%
J 0
(-5125 3475);
DISPLAY 0.617021 (-5125 3475);
PAINT SKYBLUE (-5125 3475);
FORCEPROP 1 LAST VOLTAGE 16V
J 0
(-5125 3525);
DISPLAY 0.617021 (-5125 3525);
PAINT SKYBLUE (-5125 3525);
FORCEPROP 1 LAST MATERIAL X7R
J 0
(-5125 3425);
DISPLAY 0.617021 (-5125 3425);
PAINT SKYBLUE (-5125 3425);
FORCEPROP 1 LASTPIN (-5175 3625) $PN 1
J 0
(-5165 3605);
DISPLAY 0.617021 (-5165 3605);
PAINT ORANGE (-5165 3605);
FORCEPROP 1 LASTPIN (-5175 3425) $PN 2
J 0
(-5165 3405);
DISPLAY 0.617021 (-5165 3405);
PAINT ORANGE (-5165 3405);
FORCEPROP 1 LAST PATH I199
J 0
(-5125 3675);
DISPLAY 0.978723 (-5125 3675);
PAINT WHITE (-5125 3675);
DISPLAY INVISIBLE (-5125 3675);
FORCEPROP 2 LAST CDS_LOCATION C4A20
J 0
(-5125 3625);
DISPLAY 0.617021 (-5125 3625);
PAINT AQUA (-5125 3625);
DISPLAY INVISIBLE (-5125 3625);
FORCEPROP 2 LAST CDS_SEC 1
J 0
(-5125 3675);
PAINT ORANGE (-5125 3675);
DISPLAY INVISIBLE (-5125 3675);
FORCEPROP 2 LAST SEC_TYPE 0402V
J 0
(-5125 3725);
DISPLAY 1.021277 (-5125 3725);
PAINT ORANGE (-5125 3725);
DISPLAY INVISIBLE (-5125 3725);
FORCEPROP 2 LAST SEC 1
J 0
(-5125 3725);
PAINT MONO (-5125 3725);
DISPLAY INVISIBLE (-5125 3725);
FORCEPROP 2 LAST CDS_LIB dev_discrete
J 0
(-5175 3525);
PAINT ORANGE (-5175 3525);
DISPLAY INVISIBLE (-5175 3525);
FORCEADD AGND_SCSI..1
(-5400 2700);
FORCEPROP 3 LASTPIN (-5400 2750) SIG_NAME AGND_PVPP_KLM\g
J 0
(-5390 2760);
DISPLAY 0.659574 (-5390 2760);
PAINT MONO (-5390 2760);
DISPLAY INVISIBLE (-5390 2760);
FORCEPROP 1 LAST HDL_POWER AGND_PVPP_KLM
J 1
(-5325 2625);
DISPLAY 0.617021 (-5325 2625);
PAINT GREEN (-5325 2625);
FORCEPROP 1 LAST PATH I200
J 0
(-5325 2700);
DISPLAY 0.872340 (-5325 2700);
PAINT AQUA (-5325 2700);
DISPLAY INVISIBLE (-5325 2700);
FORCEPROP 1 LAST VOLTAGE 0.0V
J 0
(-5445 2657);
DISPLAY 0.340426 (-5445 2657);
PAINT SKYBLUE (-5445 2657);
DISPLAY INVISIBLE (-5445 2657);
FORCEPROP 2 LAST BOM_COST PVPP_KLM_VR
J 0
(-5550 2650);
DISPLAY 1.042553 (-5550 2650);
PAINT WHITE (-5550 2650);
DISPLAY INVISIBLE (-5550 2650);
FORCEPROP 2 LAST CDS_LIB mstr_symbols
J 0
(-5400 2700);
PAINT MONO (-5400 2700);
DISPLAY INVISIBLE (-5400 2700);
FORCEPROP 1 LAST BODY_TYPE PLUMBING
J 0
(-5445 2657);
DISPLAY 0.340426 (-5445 2657);
PAINT GREEN (-5445 2657);
DISPLAY INVISIBLE (-5445 2657);
FORCEPROP 2 LAST ROOM PVPP_KLM_VR
J 0
(-5550 2650);
DISPLAY 1.042553 (-5550 2650);
PAINT GREEN (-5550 2650);
DISPLAY INVISIBLE (-5550 2650);
FORCEADD RES..1
(-3350 975);
FORCEPROP 1 LAST PART_NUMBER G21796-250
J 0
(-3400 1075);
DISPLAY 0.617021 (-3400 1075);
PAINT BLUE (-3400 1075);
FORCEPROP 1 LAST VALUE 22.1
J 2
(-3375 875);
DISPLAY 0.617021 (-3375 875);
PAINT SKYBLUE (-3375 875);
FORCEPROP 1 LAST TOLERANCE 1.0%
J 0
(-3350 875);
DISPLAY 0.617021 (-3350 875);
PAINT SKYBLUE (-3350 875);
FORCEPROP 1 LAST WATTAGE 1/16W
J 2
(-3375 825);
DISPLAY 0.617021 (-3375 825);
PAINT SKYBLUE (-3375 825);
FORCEPROP 1 LAST PACK_TYPE 0402
J 0
(-3100 825);
DISPLAY 0.617021 (-3100 825);
PAINT SKYBLUE (-3100 825);
FORCEPROP 1 LAST LOCATION R4B7
J 0
(-3400 1025);
DISPLAY 0.617021 (-3400 1025);
PAINT AQUA (-3400 1025);
FORCEPROP 1 LASTPIN (-3250 975) $PN 2
J 0
(-3288 987);
DISPLAY 0.617021 (-3288 987);
PAINT ORANGE (-3288 987);
FORCEPROP 1 LAST MATERIAL CHIP
J 0
(-3350 825);
DISPLAY 0.617021 (-3350 825);
PAINT SKYBLUE (-3350 825);
FORCEPROP 1 LASTPIN (-3450 975) $PN 1
J 0
(-3438 987);
DISPLAY 0.617021 (-3438 987);
PAINT ORANGE (-3438 987);
FORCEPROP 2 LAST SEC_TYPE 0402
J 0
(-3400 1175);
DISPLAY 1.021277 (-3400 1175);
PAINT ORANGE (-3400 1175);
DISPLAY INVISIBLE (-3400 1175);
FORCEPROP 2 LAST SEC 1
J 0
(-3400 1175);
DISPLAY 0.680851 (-3400 1175);
PAINT MONO (-3400 1175);
DISPLAY INVISIBLE (-3400 1175);
FORCEPROP 2 LAST CDS_LOCATION R4B7
J 0
(-3400 1025);
DISPLAY 0.617021 (-3400 1025);
PAINT AQUA (-3400 1025);
DISPLAY INVISIBLE (-3400 1025);
FORCEPROP 1 LAST PATH I201
J 0
(-3400 1125);
DISPLAY 0.978723 (-3400 1125);
PAINT WHITE (-3400 1125);
DISPLAY INVISIBLE (-3400 1125);
FORCEPROP 2 LAST ROOM PVPP_KLM_VR
J 0
(-3400 1075);
DISPLAY 1.361702 (-3400 1075);
PAINT ORANGE (-3400 1075);
DISPLAY INVISIBLE (-3400 1075);
FORCEPROP 2 LAST CDS_LIB mstr_discrete
J 0
(-3350 975);
PAINT MONO (-3350 975);
DISPLAY INVISIBLE (-3350 975);
FORCEADD CAP..1
(-6750 4150);
FORCEPROP 1 LAST VOLTAGE 16V
J 0
(-6700 4150);
DISPLAY 0.617021 (-6700 4150);
PAINT SKYBLUE (-6700 4150);
FORCEPROP 1 LAST PACK_TYPE 0805
J 0
(-6700 3950);
DISPLAY 0.617021 (-6700 3950);
PAINT SKYBLUE (-6700 3950);
FORCEPROP 1 LASTPIN (-6750 4050) $PN 2
J 0
(-6740 4030);
DISPLAY 0.617021 (-6740 4030);
PAINT ORANGE (-6740 4030);
FORCEPROP 1 LAST TOLERANCE 10%
J 0
(-6700 4100);
DISPLAY 0.617021 (-6700 4100);
PAINT SKYBLUE (-6700 4100);
FORCEPROP 1 LAST VALUE 10UF
J 0
(-6700 4200);
DISPLAY 0.617021 (-6700 4200);
PAINT SKYBLUE (-6700 4200);
FORCEPROP 1 LASTPIN (-6750 4250) $PN 1
J 0
(-6740 4230);
DISPLAY 0.617021 (-6740 4230);
PAINT ORANGE (-6740 4230);
FORCEPROP 1 LAST LOCATION C6L10
J 0
(-6700 4250);
DISPLAY 0.617021 (-6700 4250);
PAINT AQUA (-6700 4250);
FORCEPROP 1 LAST PART_NUMBER C95333-007
J 0
(-6700 4000);
DISPLAY 0.617021 (-6700 4000);
PAINT BLUE (-6700 4000);
FORCEPROP 1 LAST MATERIAL X6S
J 0
(-6700 4050);
DISPLAY 0.617021 (-6700 4050);
PAINT SKYBLUE (-6700 4050);
FORCEPROP 1 LAST PATH I202
J 0
(-6700 4300);
DISPLAY 0.978723 (-6700 4300);
PAINT WHITE (-6700 4300);
DISPLAY INVISIBLE (-6700 4300);
FORCEPROP 2 LAST SEC 1
J 0
(-6700 4350);
DISPLAY 0.680851 (-6700 4350);
PAINT MONO (-6700 4350);
DISPLAY INVISIBLE (-6700 4350);
FORCEPROP 2 LAST SEC_TYPE 0805
J 0
(-6700 4350);
DISPLAY 1.021277 (-6700 4350);
PAINT ORANGE (-6700 4350);
DISPLAY INVISIBLE (-6700 4350);
FORCEPROP 2 LAST CDS_LOCATION C6L10
J 0
(-6700 4250);
DISPLAY 0.617021 (-6700 4250);
PAINT AQUA (-6700 4250);
DISPLAY INVISIBLE (-6700 4250);
FORCEPROP 2 LAST CDS_LIB mstr_discrete
J 0
(-6750 4150);
PAINT MONO (-6750 4150);
DISPLAY INVISIBLE (-6750 4150);
FORCEADD CAP..1
(-6375 4150);
FORCEPROP 1 LAST TOLERANCE 10%
J 0
(-6325 4100);
DISPLAY 0.617021 (-6325 4100);
PAINT SKYBLUE (-6325 4100);
FORCEPROP 1 LAST MATERIAL X6S
J 0
(-6325 4050);
DISPLAY 0.617021 (-6325 4050);
PAINT SKYBLUE (-6325 4050);
FORCEPROP 1 LASTPIN (-6375 4050) $PN 2
J 0
(-6365 4030);
DISPLAY 0.617021 (-6365 4030);
PAINT ORANGE (-6365 4030);
FORCEPROP 1 LAST VOLTAGE 16V
J 0
(-6325 4150);
DISPLAY 0.617021 (-6325 4150);
PAINT SKYBLUE (-6325 4150);
FORCEPROP 1 LAST PACK_TYPE 0805
J 0
(-6325 3950);
DISPLAY 0.617021 (-6325 3950);
PAINT SKYBLUE (-6325 3950);
FORCEPROP 1 LAST PART_NUMBER C95333-007
J 0
(-6325 4000);
DISPLAY 0.617021 (-6325 4000);
PAINT BLUE (-6325 4000);
FORCEPROP 1 LASTPIN (-6375 4250) $PN 1
J 0
(-6365 4230);
DISPLAY 0.617021 (-6365 4230);
PAINT ORANGE (-6365 4230);
FORCEPROP 1 LAST LOCATION C6M3
J 0
(-6325 4250);
DISPLAY 0.617021 (-6325 4250);
PAINT AQUA (-6325 4250);
FORCEPROP 1 LAST VALUE 10UF
J 0
(-6325 4200);
DISPLAY 0.617021 (-6325 4200);
PAINT SKYBLUE (-6325 4200);
FORCEPROP 2 LAST CDS_LIB mstr_discrete
J 0
(-6375 4150);
PAINT MONO (-6375 4150);
DISPLAY INVISIBLE (-6375 4150);
FORCEPROP 2 LAST CDS_LOCATION C6M3
J 0
(-6325 4250);
DISPLAY 0.617021 (-6325 4250);
PAINT AQUA (-6325 4250);
DISPLAY INVISIBLE (-6325 4250);
FORCEPROP 2 LAST SEC_TYPE 0805
J 0
(-6325 4350);
DISPLAY 1.021277 (-6325 4350);
PAINT ORANGE (-6325 4350);
DISPLAY INVISIBLE (-6325 4350);
FORCEPROP 2 LAST SEC 1
J 0
(-6325 4350);
DISPLAY 0.680851 (-6325 4350);
PAINT MONO (-6325 4350);
DISPLAY INVISIBLE (-6325 4350);
FORCEPROP 1 LAST PATH I203
J 0
(-6325 4300);
DISPLAY 0.978723 (-6325 4300);
PAINT WHITE (-6325 4300);
DISPLAY INVISIBLE (-6325 4300);
FORCEADD CAP..1
(-5925 4150);
FORCEPROP 1 LAST PACK_TYPE 0805
J 0
(-5875 3950);
DISPLAY 0.617021 (-5875 3950);
PAINT SKYBLUE (-5875 3950);
FORCEPROP 1 LASTPIN (-5925 4050) $PN 2
J 0
(-5915 4030);
DISPLAY 0.617021 (-5915 4030);
PAINT ORANGE (-5915 4030);
FORCEPROP 1 LAST MATERIAL X6S
J 0
(-5875 4050);
DISPLAY 0.617021 (-5875 4050);
PAINT SKYBLUE (-5875 4050);
FORCEPROP 1 LAST TOLERANCE 10%
J 0
(-5875 4100);
DISPLAY 0.617021 (-5875 4100);
PAINT SKYBLUE (-5875 4100);
FORCEPROP 1 LAST PART_NUMBER C95333-007
J 0
(-5875 4000);
DISPLAY 0.617021 (-5875 4000);
PAINT BLUE (-5875 4000);
FORCEPROP 1 LASTPIN (-5925 4250) $PN 1
J 0
(-5915 4230);
DISPLAY 0.617021 (-5915 4230);
PAINT ORANGE (-5915 4230);
FORCEPROP 1 LAST VALUE 10UF
J 0
(-5875 4200);
DISPLAY 0.617021 (-5875 4200);
PAINT SKYBLUE (-5875 4200);
FORCEPROP 1 LAST LOCATION C6M5
J 0
(-5875 4250);
DISPLAY 0.617021 (-5875 4250);
PAINT AQUA (-5875 4250);
FORCEPROP 1 LAST VOLTAGE 16V
J 0
(-5875 4150);
DISPLAY 0.617021 (-5875 4150);
PAINT SKYBLUE (-5875 4150);
FORCEPROP 2 LAST CDS_LIB mstr_discrete
J 0
(-5925 4150);
PAINT MONO (-5925 4150);
DISPLAY INVISIBLE (-5925 4150);
FORCEPROP 1 LAST PATH I204
J 0
(-5875 4300);
DISPLAY 0.978723 (-5875 4300);
PAINT WHITE (-5875 4300);
DISPLAY INVISIBLE (-5875 4300);
FORCEPROP 2 LAST CDS_LOCATION C6M5
J 0
(-5875 4250);
DISPLAY 0.617021 (-5875 4250);
PAINT AQUA (-5875 4250);
DISPLAY INVISIBLE (-5875 4250);
FORCEPROP 2 LAST SEC 1
J 0
(-5875 4350);
DISPLAY 0.680851 (-5875 4350);
PAINT MONO (-5875 4350);
DISPLAY INVISIBLE (-5875 4350);
FORCEPROP 2 LAST SEC_TYPE 0805
J 0
(-5875 4350);
DISPLAY 1.021277 (-5875 4350);
PAINT ORANGE (-5875 4350);
DISPLAY INVISIBLE (-5875 4350);
FORCEADD CAP..1
(-5475 4150);
FORCEPROP 1 LAST PART_NUMBER C95333-007
J 0
(-5425 4000);
DISPLAY 0.617021 (-5425 4000);
PAINT BLUE (-5425 4000);
FORCEPROP 1 LASTPIN (-5475 4050) $PN 2
J 0
(-5465 4030);
DISPLAY 0.617021 (-5465 4030);
PAINT ORANGE (-5465 4030);
FORCEPROP 1 LAST MATERIAL X6S
J 0
(-5425 4050);
DISPLAY 0.617021 (-5425 4050);
PAINT SKYBLUE (-5425 4050);
FORCEPROP 1 LAST PACK_TYPE 0805
J 0
(-5425 3950);
DISPLAY 0.617021 (-5425 3950);
PAINT SKYBLUE (-5425 3950);
FORCEPROP 1 LAST TOLERANCE 10%
J 0
(-5425 4100);
DISPLAY 0.617021 (-5425 4100);
PAINT SKYBLUE (-5425 4100);
FORCEPROP 1 LASTPIN (-5475 4250) $PN 1
J 0
(-5465 4230);
DISPLAY 0.617021 (-5465 4230);
PAINT ORANGE (-5465 4230);
FORCEPROP 1 LAST VOLTAGE 16V
J 0
(-5425 4150);
DISPLAY 0.617021 (-5425 4150);
PAINT SKYBLUE (-5425 4150);
FORCEPROP 1 LAST VALUE 10UF
J 0
(-5425 4200);
DISPLAY 0.617021 (-5425 4200);
PAINT SKYBLUE (-5425 4200);
FORCEPROP 1 LAST LOCATION C4A19
J 0
(-5425 4250);
DISPLAY 0.617021 (-5425 4250);
PAINT AQUA (-5425 4250);
FORCEPROP 2 LAST CDS_LIB mstr_discrete
J 0
(-5475 4150);
PAINT MONO (-5475 4150);
DISPLAY INVISIBLE (-5475 4150);
FORCEPROP 2 LAST CDS_LOCATION C4A19
J 0
(-5425 4250);
DISPLAY 0.617021 (-5425 4250);
PAINT AQUA (-5425 4250);
DISPLAY INVISIBLE (-5425 4250);
FORCEPROP 2 LAST SEC_TYPE 0805
J 0
(-5425 4350);
DISPLAY 1.021277 (-5425 4350);
PAINT ORANGE (-5425 4350);
DISPLAY INVISIBLE (-5425 4350);
FORCEPROP 2 LAST SEC 1
J 0
(-5425 4350);
DISPLAY 0.680851 (-5425 4350);
PAINT MONO (-5425 4350);
DISPLAY INVISIBLE (-5425 4350);
FORCEPROP 1 LAST PATH I205
J 0
(-5425 4300);
DISPLAY 0.978723 (-5425 4300);
PAINT WHITE (-5425 4300);
DISPLAY INVISIBLE (-5425 4300);
FORCEADD GND..1
(-6750 3900);
FORCEPROP 3 LASTPIN (-6750 3950) SIG_NAME GND\g
J 0
(-6740 3960);
DISPLAY 0.659574 (-6740 3960);
PAINT MONO (-6740 3960);
DISPLAY INVISIBLE (-6740 3960);
FORCEPROP 2 LAST BOM_COST PVPP_KLM_VR
J 0
(-7600 3975);
DISPLAY 1.042553 (-7600 3975);
PAINT WHITE (-7600 3975);
DISPLAY INVISIBLE (-7600 3975);
FORCEPROP 2 LAST ROOM PVPP_KLM_VR
J 0
(-7325 3975);
DISPLAY 1.042553 (-7325 3975);
PAINT GREEN (-7325 3975);
DISPLAY INVISIBLE (-7325 3975);
FORCEPROP 1 LAST BODY_TYPE PLUMBING
J 0
(-6795 3857);
DISPLAY 0.340426 (-6795 3857);
PAINT GREEN (-6795 3857);
DISPLAY INVISIBLE (-6795 3857);
FORCEPROP 1 LAST VOLTAGE 0
J 0
(-6750 3900);
PAINT SKYBLUE (-6750 3900);
DISPLAY INVISIBLE (-6750 3900);
FORCEPROP 2 LAST CDS_LIB mstr_symbols
J 0
(-6750 3900);
PAINT MONO (-6750 3900);
DISPLAY INVISIBLE (-6750 3900);
FORCEPROP 1 LAST SIZE 1B
J 0
(-6675 3850);
DISPLAY 0.872340 (-6675 3850);
PAINT GREEN (-6675 3850);
DISPLAY INVISIBLE (-6675 3850);
FORCEPROP 1 LAST PATH I206
J 0
(-6675 3900);
DISPLAY 0.872340 (-6675 3900);
PAINT AQUA (-6675 3900);
DISPLAY INVISIBLE (-6675 3900);
FORCEPROP 1 LAST HDL_POWER GND
J 0
(-6750 4050);
DISPLAY 0.872340 (-6750 4050);
PAINT GREEN (-6750 4050);
DISPLAY INVISIBLE (-6750 4050);
FORCEADD GND..1
(-6375 3900);
FORCEPROP 3 LASTPIN (-6375 3950) SIG_NAME GND\g
J 0
(-6365 3960);
DISPLAY 0.659574 (-6365 3960);
PAINT MONO (-6365 3960);
DISPLAY INVISIBLE (-6365 3960);
FORCEPROP 1 LAST HDL_POWER GND
J 0
(-6375 4050);
DISPLAY 0.872340 (-6375 4050);
PAINT GREEN (-6375 4050);
DISPLAY INVISIBLE (-6375 4050);
FORCEPROP 1 LAST PATH I207
J 0
(-6300 3900);
DISPLAY 0.872340 (-6300 3900);
PAINT AQUA (-6300 3900);
DISPLAY INVISIBLE (-6300 3900);
FORCEPROP 1 LAST SIZE 1B
J 0
(-6300 3850);
DISPLAY 0.872340 (-6300 3850);
PAINT GREEN (-6300 3850);
DISPLAY INVISIBLE (-6300 3850);
FORCEPROP 2 LAST CDS_LIB mstr_symbols
J 0
(-6375 3900);
PAINT MONO (-6375 3900);
DISPLAY INVISIBLE (-6375 3900);
FORCEPROP 1 LAST VOLTAGE 0
J 0
(-6375 3900);
PAINT SKYBLUE (-6375 3900);
DISPLAY INVISIBLE (-6375 3900);
FORCEPROP 1 LAST BODY_TYPE PLUMBING
J 0
(-6420 3857);
DISPLAY 0.340426 (-6420 3857);
PAINT GREEN (-6420 3857);
DISPLAY INVISIBLE (-6420 3857);
FORCEPROP 2 LAST ROOM PVPP_KLM_VR
J 0
(-6950 3975);
DISPLAY 1.042553 (-6950 3975);
PAINT GREEN (-6950 3975);
DISPLAY INVISIBLE (-6950 3975);
FORCEPROP 2 LAST BOM_COST PVPP_KLM_VR
J 0
(-7225 3975);
DISPLAY 1.042553 (-7225 3975);
PAINT WHITE (-7225 3975);
DISPLAY INVISIBLE (-7225 3975);
FORCEADD GND..1
(-5925 3900);
FORCEPROP 3 LASTPIN (-5925 3950) SIG_NAME GND\g
J 0
(-5915 3960);
DISPLAY 0.659574 (-5915 3960);
PAINT MONO (-5915 3960);
DISPLAY INVISIBLE (-5915 3960);
FORCEPROP 1 LAST SIZE 1B
J 0
(-5850 3850);
DISPLAY 0.872340 (-5850 3850);
PAINT GREEN (-5850 3850);
DISPLAY INVISIBLE (-5850 3850);
FORCEPROP 1 LAST PATH I208
J 0
(-5850 3900);
DISPLAY 0.872340 (-5850 3900);
PAINT AQUA (-5850 3900);
DISPLAY INVISIBLE (-5850 3900);
FORCEPROP 1 LAST HDL_POWER GND
J 0
(-5925 4050);
DISPLAY 0.872340 (-5925 4050);
PAINT GREEN (-5925 4050);
DISPLAY INVISIBLE (-5925 4050);
FORCEPROP 1 LAST BODY_TYPE PLUMBING
J 0
(-5970 3857);
DISPLAY 0.340426 (-5970 3857);
PAINT GREEN (-5970 3857);
DISPLAY INVISIBLE (-5970 3857);
FORCEPROP 2 LAST CDS_LIB mstr_symbols
J 0
(-5925 3900);
PAINT MONO (-5925 3900);
DISPLAY INVISIBLE (-5925 3900);
FORCEPROP 1 LAST VOLTAGE 0
J 0
(-5925 3900);
PAINT SKYBLUE (-5925 3900);
DISPLAY INVISIBLE (-5925 3900);
FORCEPROP 2 LAST ROOM PVPP_KLM_VR
J 0
(-6500 3975);
DISPLAY 1.042553 (-6500 3975);
PAINT GREEN (-6500 3975);
DISPLAY INVISIBLE (-6500 3975);
FORCEPROP 2 LAST BOM_COST PVPP_KLM_VR
J 0
(-6775 3975);
DISPLAY 1.042553 (-6775 3975);
PAINT WHITE (-6775 3975);
DISPLAY INVISIBLE (-6775 3975);
FORCEADD GND..1
(-5475 3900);
FORCEPROP 3 LASTPIN (-5475 3950) SIG_NAME GND\g
J 0
(-5465 3960);
DISPLAY 0.659574 (-5465 3960);
PAINT MONO (-5465 3960);
DISPLAY INVISIBLE (-5465 3960);
FORCEPROP 1 LAST HDL_POWER GND
J 0
(-5475 4050);
DISPLAY 0.872340 (-5475 4050);
PAINT GREEN (-5475 4050);
DISPLAY INVISIBLE (-5475 4050);
FORCEPROP 1 LAST SIZE 1B
J 0
(-5400 3850);
DISPLAY 0.872340 (-5400 3850);
PAINT GREEN (-5400 3850);
DISPLAY INVISIBLE (-5400 3850);
FORCEPROP 2 LAST CDS_LIB mstr_symbols
J 0
(-5475 3900);
PAINT MONO (-5475 3900);
DISPLAY INVISIBLE (-5475 3900);
FORCEPROP 1 LAST PATH I209
J 0
(-5400 3900);
DISPLAY 0.872340 (-5400 3900);
PAINT AQUA (-5400 3900);
DISPLAY INVISIBLE (-5400 3900);
FORCEPROP 1 LAST VOLTAGE 0
J 0
(-5475 3900);
PAINT SKYBLUE (-5475 3900);
DISPLAY INVISIBLE (-5475 3900);
FORCEPROP 1 LAST BODY_TYPE PLUMBING
J 0
(-5520 3857);
DISPLAY 0.340426 (-5520 3857);
PAINT GREEN (-5520 3857);
DISPLAY INVISIBLE (-5520 3857);
FORCEPROP 2 LAST ROOM PVPP_KLM_VR
J 0
(-6050 3975);
DISPLAY 1.042553 (-6050 3975);
PAINT GREEN (-6050 3975);
DISPLAY INVISIBLE (-6050 3975);
FORCEPROP 2 LAST BOM_COST PVPP_KLM_VR
J 0
(-6325 3975);
DISPLAY 1.042553 (-6325 3975);
PAINT WHITE (-6325 3975);
DISPLAY INVISIBLE (-6325 3975);
FORCEADD CAPP..1
(-1450 3650);
FORCEPROP 1 LAST LOCATION C6L8
J 0
(-1400 3800);
DISPLAY 0.617021 (-1400 3800);
PAINT AQUA (-1400 3800);
FORCEPROP 1 LAST VALUE 220UF
J 0
(-1400 3750);
DISPLAY 0.617021 (-1400 3750);
PAINT SKYBLUE (-1400 3750);
FORCEPROP 1 LAST TOLERANCE 20%
J 0
(-1400 3700);
DISPLAY 0.617021 (-1400 3700);
PAINT SKYBLUE (-1400 3700);
FORCEPROP 1 LAST VOLTAGE 4V
J 0
(-1400 3650);
DISPLAY 0.617021 (-1400 3650);
PAINT SKYBLUE (-1400 3650);
FORCEPROP 1 LASTPIN (-1450 3750) $PN 1
J 0
(-1440 3735);
DISPLAY 0.617021 (-1440 3735);
PAINT ORANGE (-1440 3735);
FORCEPROP 1 LASTPIN (-1450 3550) $PN 2
J 0
(-1440 3535);
DISPLAY 0.617021 (-1440 3535);
PAINT ORANGE (-1440 3535);
FORCEPROP 0 LAST GROUP PWR_BULK_CAP
J 0
(-1385 3401);
DISPLAY 0.638298 (-1385 3401);
PAINT BROWN (-1385 3401);
DISPLAY BOTH (-1385 3401);
FORCEPROP 1 LAST MATERIAL POSCAP
J 0
(-1400 3600);
DISPLAY 0.617021 (-1400 3600);
PAINT SKYBLUE (-1400 3600);
FORCEPROP 1 LAST PACK_TYPE 7343
J 0
(-1400 3550);
DISPLAY 0.617021 (-1400 3550);
PAINT SKYBLUE (-1400 3550);
FORCEPROP 1 LAST PART_NUMBER 724613-067
J 0
(-1400 3500);
DISPLAY 0.617021 (-1400 3500);
PAINT BLUE (-1400 3500);
FORCEPROP 2 LAST SEC_TYPE 7343
J 0
(-1400 3850);
DISPLAY 1.021277 (-1400 3850);
PAINT ORANGE (-1400 3850);
DISPLAY INVISIBLE (-1400 3850);
FORCEPROP 2 LAST SEC 1
J 0
(-1400 3850);
DISPLAY 0.680851 (-1400 3850);
PAINT MONO (-1400 3850);
DISPLAY INVISIBLE (-1400 3850);
FORCEPROP 1 LAST PATH I210
J 0
(-1400 3800);
DISPLAY 0.978723 (-1400 3800);
PAINT ORANGE (-1400 3800);
DISPLAY INVISIBLE (-1400 3800);
FORCEPROP 2 LAST CDS_LOCATION C6L8
J 0
(-1400 3750);
DISPLAY 0.617021 (-1400 3750);
PAINT AQUA (-1400 3750);
DISPLAY INVISIBLE (-1400 3750);
FORCEPROP 2 LAST CDS_LIB mstr_discrete
J 0
(-1450 3650);
PAINT ORANGE (-1450 3650);
DISPLAY INVISIBLE (-1450 3650);
FORCEADD CAP..2
R 2
(-2850 2450);
FORCEPROP 1 LAST PART_NUMBER A36096-075
J 1
(-2800 2375);
DISPLAY 0.617021 (-2800 2375);
PAINT BLUE (-2800 2375);
FORCEPROP 1 LAST VOLTAGE 50V
J 2
(-2850 2325);
DISPLAY 0.617021 (-2850 2325);
PAINT SKYBLUE (-2850 2325);
FORCEPROP 1 LAST PACK_TYPE 0402LF
J 1
(-2850 2225);
DISPLAY 0.617021 (-2850 2225);
PAINT SKYBLUE (-2850 2225);
FORCEPROP 1 LASTPIN (-2750 2450) $PN 1
J 2
(-2740 2465);
DISPLAY 0.617021 (-2740 2465);
PAINT ORANGE (-2740 2465);
FORCEPROP 1 LAST TOLERANCE 10%
J 0
(-2825 2275);
DISPLAY 0.617021 (-2825 2275);
PAINT SKYBLUE (-2825 2275);
FORCEPROP 1 LAST LOCATION C4B9
J 1
(-2850 2525);
DISPLAY 0.617021 (-2850 2525);
PAINT AQUA (-2850 2525);
FORCEPROP 1 LASTPIN (-2950 2450) $PN 2
J 2
(-2935 2465);
DISPLAY 0.617021 (-2935 2465);
PAINT ORANGE (-2935 2465);
FORCEPROP 1 LAST MATERIAL X7R
J 2
(-2825 2275);
DISPLAY 0.617021 (-2825 2275);
PAINT SKYBLUE (-2825 2275);
FORCEPROP 1 LAST VALUE 2200PF
J 0
(-2825 2325);
DISPLAY 0.617021 (-2825 2325);
PAINT SKYBLUE (-2825 2325);
FORCEPROP 2 LAST ROOM PVPP_KLM_VR
J 2
(-2850 2575);
DISPLAY 0.765957 (-2850 2575);
PAINT GREEN (-2850 2575);
DISPLAY INVISIBLE (-2850 2575);
FORCEPROP 1 LAST PATH I211
J 2
(-2850 2650);
DISPLAY 0.978723 (-2850 2650);
PAINT WHITE (-2850 2650);
DISPLAY INVISIBLE (-2850 2650);
FORCEPROP 2 LAST SEC 1
J 0
(-2850 2700);
DISPLAY 0.680851 (-2850 2700);
PAINT MONO (-2850 2700);
DISPLAY INVISIBLE (-2850 2700);
FORCEPROP 2 LAST REUSE_ID 27
J 0
(-2850 2700);
DISPLAY 1.042553 (-2850 2700);
PAINT ORANGE (-2850 2700);
DISPLAY INVISIBLE (-2850 2700);
FORCEPROP 2 LAST BOM_COST PVPP_KLM_VR
J 0
(-2895 2610);
DISPLAY 1.042553 (-2895 2610);
PAINT WHITE (-2895 2610);
DISPLAY INVISIBLE (-2895 2610);
FORCEPROP 2 LAST SEC_TYPE 0402LF
J 0
(-2850 2700);
DISPLAY 1.021277 (-2850 2700);
PAINT ORANGE (-2850 2700);
DISPLAY INVISIBLE (-2850 2700);
FORCEPROP 2 LAST CDS_LOCATION C4B9
J 1
(-2850 2525);
DISPLAY 0.617021 (-2850 2525);
PAINT AQUA (-2850 2525);
DISPLAY INVISIBLE (-2850 2525);
FORCEPROP 2 LAST CDS_LIB mstr_discrete
J 0
(-2850 2450);
PAINT ORANGE (-2850 2450);
DISPLAY INVISIBLE (-2850 2450);
FORCEADD CAP..2
R 2
(-2225 2825);
FORCEPROP 1 LAST PACK_TYPE 0402LF
J 1
(-2200 2650);
DISPLAY 0.617021 (-2200 2650);
PAINT SKYBLUE (-2200 2650);
FORCEPROP 1 LAST TOLERANCE 5%
J 0
(-2125 2700);
DISPLAY 0.617021 (-2125 2700);
PAINT SKYBLUE (-2125 2700);
FORCEPROP 1 LAST PART_NUMBER A36095-026
J 1
(-2275 2700);
DISPLAY 0.617021 (-2275 2700);
PAINT BLUE (-2275 2700);
FORCEPROP 1 LAST VALUE 100.0PF
J 0
(-2300 2750);
DISPLAY 0.617021 (-2300 2750);
PAINT SKYBLUE (-2300 2750);
FORCEPROP 1 LAST VOLTAGE 50V
J 2
(-2325 2750);
DISPLAY 0.617021 (-2325 2750);
PAINT SKYBLUE (-2325 2750);
FORCEPROP 1 LAST MATERIAL COG
J 2
(-2025 2750);
DISPLAY 0.617021 (-2025 2750);
PAINT SKYBLUE (-2025 2750);
FORCEPROP 1 LAST LOCATION C4B4
J 1
(-2225 2875);
DISPLAY 0.617021 (-2225 2875);
PAINT AQUA (-2225 2875);
FORCEPROP 1 LASTPIN (-2325 2825) $PN 2
J 2
(-2310 2840);
DISPLAY 0.617021 (-2310 2840);
PAINT ORANGE (-2310 2840);
FORCEPROP 1 LASTPIN (-2125 2825) $PN 1
J 2
(-2115 2840);
DISPLAY 0.617021 (-2115 2840);
PAINT ORANGE (-2115 2840);
FORCEPROP 2 LAST ROOM PVPP_KLM_VR
J 2
(-2225 2950);
DISPLAY 0.765957 (-2225 2950);
PAINT GREEN (-2225 2950);
DISPLAY INVISIBLE (-2225 2950);
FORCEPROP 1 LAST PATH I212
J 2
(-2225 3025);
DISPLAY 0.978723 (-2225 3025);
PAINT WHITE (-2225 3025);
DISPLAY INVISIBLE (-2225 3025);
FORCEPROP 2 LAST CDS_LOCATION C4B4
J 1
(-2225 2875);
DISPLAY 0.617021 (-2225 2875);
PAINT AQUA (-2225 2875);
DISPLAY INVISIBLE (-2225 2875);
FORCEPROP 2 LAST BOM_COST PVPP_KLM_VR
J 0
(-2270 2985);
DISPLAY 1.042553 (-2270 2985);
PAINT WHITE (-2270 2985);
DISPLAY INVISIBLE (-2270 2985);
FORCEPROP 2 LAST CDS_LIB mstr_discrete
J 0
(-2225 2825);
PAINT ORANGE (-2225 2825);
DISPLAY INVISIBLE (-2225 2825);
FORCEPROP 2 LAST SEC 1
J 0
(-2225 3075);
DISPLAY 0.680851 (-2225 3075);
PAINT MONO (-2225 3075);
DISPLAY INVISIBLE (-2225 3075);
FORCEPROP 2 LAST REUSE_ID 27
J 0
(-2225 3075);
DISPLAY 1.042553 (-2225 3075);
PAINT ORANGE (-2225 3075);
DISPLAY INVISIBLE (-2225 3075);
FORCEPROP 2 LAST SEC_TYPE 0402LF
J 0
(-2225 3075);
DISPLAY 1.021277 (-2225 3075);
PAINT ORANGE (-2225 3075);
DISPLAY INVISIBLE (-2225 3075);
FORCEADD RES..1
(-2150 2450);
FORCEPROP 1 LAST VALUE 7.87K
J 2
(-2250 2325);
DISPLAY 0.617021 (-2250 2325);
PAINT SKYBLUE (-2250 2325);
FORCEPROP 1 LAST LOCATION R4B8
J 0
(-2200 2500);
DISPLAY 0.617021 (-2200 2500);
PAINT AQUA (-2200 2500);
FORCEPROP 1 LAST PART_NUMBER G21796-242
J 0
(-2300 2375);
DISPLAY 0.617021 (-2300 2375);
PAINT BLUE (-2300 2375);
FORCEPROP 1 LAST PACK_TYPE 0402
J 0
(-2100 2325);
DISPLAY 0.617021 (-2100 2325);
PAINT SKYBLUE (-2100 2325);
FORCEPROP 1 LAST MATERIAL CHIP
J 0
(-2150 2275);
DISPLAY 0.617021 (-2150 2275);
PAINT SKYBLUE (-2150 2275);
FORCEPROP 1 LASTPIN (-2050 2450) $PN 2
J 0
(-2088 2462);
DISPLAY 0.617021 (-2088 2462);
PAINT ORANGE (-2088 2462);
FORCEPROP 1 LAST TOLERANCE 1.0%
J 0
(-2200 2325);
DISPLAY 0.617021 (-2200 2325);
PAINT SKYBLUE (-2200 2325);
FORCEPROP 1 LASTPIN (-2250 2450) $PN 1
J 0
(-2238 2462);
DISPLAY 0.617021 (-2238 2462);
PAINT ORANGE (-2238 2462);
FORCEPROP 1 LAST WATTAGE 1/16W
J 2
(-2175 2275);
DISPLAY 0.617021 (-2175 2275);
PAINT SKYBLUE (-2175 2275);
FORCEPROP 1 LAST PATH I213
J 0
(-2200 2600);
DISPLAY 0.978723 (-2200 2600);
PAINT WHITE (-2200 2600);
DISPLAY INVISIBLE (-2200 2600);
FORCEPROP 2 LAST REUSE_ID 13
J 0
(-2200 2650);
DISPLAY 1.042553 (-2200 2650);
PAINT ORANGE (-2200 2650);
DISPLAY INVISIBLE (-2200 2650);
FORCEPROP 2 LAST SEC_TYPE 0402
J 0
(-2200 2650);
DISPLAY 1.021277 (-2200 2650);
PAINT ORANGE (-2200 2650);
DISPLAY INVISIBLE (-2200 2650);
FORCEPROP 0 LAST SEC 1
J 0
(-2200 2550);
PAINT MONO (-2200 2550);
DISPLAY INVISIBLE (-2200 2550);
FORCEPROP 2 LAST ROOM PVPP_KLM_VR
J 0
(-2150 2450);
PAINT GREEN (-2150 2450);
DISPLAY INVISIBLE (-2150 2450);
FORCEPROP 2 LAST CDS_LIB mstr_discrete
J 0
(-2150 2450);
PAINT MONO (-2150 2450);
DISPLAY INVISIBLE (-2150 2450);
FORCEPROP 2 LAST BOM_COST PVPP_KLM_VR
J 0
(-2150 2450);
PAINT WHITE (-2150 2450);
DISPLAY INVISIBLE (-2150 2450);
FORCEPROP 2 LAST CDS_LOCATION R4B8
J 0
(-2200 2500);
DISPLAY 0.617021 (-2200 2500);
PAINT AQUA (-2200 2500);
DISPLAY INVISIBLE (-2200 2500);
FORCEADD RES..1
R 5
(-1350 3050);
FORCEPROP 1 LAST PART_NUMBER G21497-005
J 0
(-1300 2975);
DISPLAY 0.617021 (-1300 2975);
PAINT BLUE (-1300 2975);
FORCEPROP 1 LAST MATERIAL CHIP
J 0
(-1300 3025);
DISPLAY 0.617021 (-1300 3025);
PAINT SKYBLUE (-1300 3025);
FORCEPROP 1 LAST PACK_TYPE 0402
J 0
(-1175 3025);
DISPLAY 0.617021 (-1175 3025);
PAINT SKYBLUE (-1175 3025);
FORCEPROP 1 LAST TOLERANCE 5%
J 0
(-1200 3075);
DISPLAY 0.617021 (-1200 3075);
PAINT SKYBLUE (-1200 3075);
FORCEPROP 1 LAST VALUE 0.0
J 0
(-1300 3075);
DISPLAY 0.617021 (-1300 3075);
PAINT SKYBLUE (-1300 3075);
FORCEPROP 1 LAST LOCATION R4B3
J 0
(-1300 3125);
DISPLAY 0.617021 (-1300 3125);
PAINT AQUA (-1300 3125);
FORCEPROP 1 LASTPIN (-1350 3150) $PN 1
J 0
(-1338 3138);
DISPLAY 0.617021 (-1338 3138);
PAINT ORANGE (-1338 3138);
FORCEPROP 1 LASTPIN (-1350 2950) $PN 2
J 0
(-1338 2988);
DISPLAY 0.617021 (-1338 2988);
PAINT ORANGE (-1338 2988);
FORCEPROP 1 LAST WATTAGE 1/16W
J 0
(-1125 3075);
DISPLAY 0.617021 (-1125 3075);
PAINT SKYBLUE (-1125 3075);
FORCEPROP 2 LAST SEC 1
J 0
(-1275 3200);
DISPLAY 0.680851 (-1275 3200);
PAINT MONO (-1275 3200);
DISPLAY INVISIBLE (-1275 3200);
FORCEPROP 2 LAST SEC_TYPE 0402
J 0
(-1275 3200);
DISPLAY 1.021277 (-1275 3200);
PAINT ORANGE (-1275 3200);
DISPLAY INVISIBLE (-1275 3200);
FORCEPROP 0 LAST SPOF TRUE
J 0
(-1300 3200);
DISPLAY 1.021277 (-1300 3200);
PAINT ORANGE (-1300 3200);
DISPLAY INVISIBLE (-1300 3200);
FORCEPROP 2 LAST CDS_LOCATION R4B3
J 0
(-1250 3000);
DISPLAY 0.617021 (-1250 3000);
PAINT AQUA (-1250 3000);
DISPLAY INVISIBLE (-1250 3000);
FORCEPROP 1 LAST PATH I214
R 3
J 0
(-1200 3100);
DISPLAY 0.978723 (-1200 3100);
PAINT WHITE (-1200 3100);
DISPLAY INVISIBLE (-1200 3100);
FORCEPROP 2 LAST ROOM PVPP_KLM_VR
R 3
J 0
(-1200 3100);
DISPLAY 1.659574 (-1200 3100);
PAINT GREEN (-1200 3100);
DISPLAY INVISIBLE (-1200 3100);
FORCEPROP 2 LAST CDS_LIB mstr_discrete
J 0
(-1350 3050);
PAINT ORANGE (-1350 3050);
DISPLAY INVISIBLE (-1350 3050);
FORCEADD RES..2
(-1350 2175);
FORCEPROP 1 LAST PART_NUMBER G21796-040
J 0
(-1335 2000);
DISPLAY 0.617021 (-1335 2000);
PAINT BLUE (-1335 2000);
FORCEPROP 1 LAST LOCATION R4B5
J 0
(-1305 2300);
DISPLAY 0.617021 (-1305 2300);
PAINT AQUA (-1305 2300);
FORCEPROP 1 LAST VALUE 20.0K
J 0
(-1305 2250);
DISPLAY 0.617021 (-1305 2250);
PAINT SKYBLUE (-1305 2250);
FORCEPROP 1 LAST TOLERANCE 1%
J 0
(-1305 2200);
DISPLAY 0.617021 (-1305 2200);
PAINT SKYBLUE (-1305 2200);
FORCEPROP 1 LAST PACK_TYPE 0402
J 0
(-1310 2100);
DISPLAY 0.617021 (-1310 2100);
PAINT SKYBLUE (-1310 2100);
FORCEPROP 1 LAST MATERIAL CHIP
J 0
(-1310 2050);
DISPLAY 0.617021 (-1310 2050);
PAINT SKYBLUE (-1310 2050);
FORCEPROP 1 LAST WATTAGE 1/16W
J 0
(-1310 2150);
DISPLAY 0.617021 (-1310 2150);
PAINT SKYBLUE (-1310 2150);
FORCEPROP 1 LASTPIN (-1350 2275) $PN 1
J 0
(-1345 2237);
DISPLAY 0.617021 (-1345 2237);
PAINT WHITE (-1345 2237);
FORCEPROP 1 LASTPIN (-1350 2075) $PN 2
J 0
(-1345 2085);
DISPLAY 0.617021 (-1345 2085);
PAINT WHITE (-1345 2085);
FORCEPROP 2 LAST $SEC 1
J 0
(-1300 2400);
DISPLAY 0.680851 (-1300 2400);
PAINT MONO (-1300 2400);
DISPLAY INVISIBLE (-1300 2400);
FORCEPROP 1 LAST PATH I215
J 0
(-1300 2350);
DISPLAY 0.978723 (-1300 2350);
PAINT WHITE (-1300 2350);
DISPLAY INVISIBLE (-1300 2350);
FORCEPROP 2 LAST REUSE_ID 9
J 0
(-1300 2400);
DISPLAY 1.042553 (-1300 2400);
PAINT ORANGE (-1300 2400);
DISPLAY INVISIBLE (-1300 2400);
FORCEPROP 2 LAST CDS_SEC 1
J 0
(-1300 2400);
DISPLAY 1.042553 (-1300 2400);
PAINT ORANGE (-1300 2400);
DISPLAY INVISIBLE (-1300 2400);
FORCEPROP 0 LAST SPOF TRUE
J 0
(-1300 2400);
DISPLAY 1.021277 (-1300 2400);
PAINT ORANGE (-1300 2400);
DISPLAY INVISIBLE (-1300 2400);
FORCEPROP 2 LAST BOM_COST PVPP_KLM_VR
J 0
(-1305 2355);
DISPLAY 1.042553 (-1305 2355);
PAINT WHITE (-1305 2355);
DISPLAY INVISIBLE (-1305 2355);
FORCEPROP 2 LAST ROOM PVPP_KLM_VR
J 0
(-1305 2330);
PAINT GREEN (-1305 2330);
DISPLAY INVISIBLE (-1305 2330);
FORCEPROP 2 LAST CDS_LOCATION R4B5
J 0
(-1305 2300);
DISPLAY 0.617021 (-1305 2300);
PAINT AQUA (-1305 2300);
DISPLAY INVISIBLE (-1305 2300);
FORCEPROP 2 LAST CDS_LIB mstr_discrete
J 0
(-1350 2175);
PAINT MONO (-1350 2175);
DISPLAY INVISIBLE (-1350 2175);
FORCEADD CAP..1
(-1025 1950);
FORCEPROP 1 LAST PART_NUMBER A36096-075
J 0
(-975 1800);
DISPLAY 0.617021 (-975 1800);
PAINT BLUE (-975 1800);
FORCEPROP 1 LAST PACK_TYPE 0402LF
J 0
(-975 1750);
DISPLAY 0.617021 (-975 1750);
PAINT SKYBLUE (-975 1750);
FORCEPROP 1 LASTPIN (-1025 2050) $PN 1
J 0
(-1015 2030);
DISPLAY 0.617021 (-1015 2030);
PAINT ORANGE (-1015 2030);
FORCEPROP 1 LASTPIN (-1025 1850) $PN 2
J 0
(-1015 1830);
DISPLAY 0.617021 (-1015 1830);
PAINT ORANGE (-1015 1830);
FORCEPROP 1 LAST MATERIAL X7R
J 0
(-975 1850);
DISPLAY 0.617021 (-975 1850);
PAINT SKYBLUE (-975 1850);
FORCEPROP 1 LAST TOLERANCE 10%
J 0
(-975 1900);
DISPLAY 0.617021 (-975 1900);
PAINT SKYBLUE (-975 1900);
FORCEPROP 1 LAST VOLTAGE 50V
J 0
(-975 1950);
DISPLAY 0.617021 (-975 1950);
PAINT SKYBLUE (-975 1950);
FORCEPROP 1 LAST VALUE 2200PF
J 0
(-975 2000);
DISPLAY 0.617021 (-975 2000);
PAINT SKYBLUE (-975 2000);
FORCEPROP 1 LAST LOCATION C4B7
J 0
(-975 2050);
DISPLAY 0.617021 (-975 2050);
PAINT AQUA (-975 2050);
FORCEPROP 2 LAST CDS_LIB mstr_discrete
J 0
(-1025 1950);
PAINT ORANGE (-1025 1950);
DISPLAY INVISIBLE (-1025 1950);
FORCEPROP 2 LAST ROOM PVPP_KLM_VR
J 0
(-975 2075);
PAINT GREEN (-975 2075);
DISPLAY INVISIBLE (-975 2075);
FORCEPROP 1 LAST PATH I218
J 0
(-975 2100);
DISPLAY 0.978723 (-975 2100);
PAINT WHITE (-975 2100);
DISPLAY INVISIBLE (-975 2100);
FORCEPROP 2 LAST CDS_LOCATION C4B7
J 0
(-975 2050);
DISPLAY 0.617021 (-975 2050);
PAINT AQUA (-975 2050);
DISPLAY INVISIBLE (-975 2050);
FORCEPROP 2 LAST SEC 1
J 0
(-975 2150);
DISPLAY 0.680851 (-975 2150);
PAINT MONO (-975 2150);
DISPLAY INVISIBLE (-975 2150);
FORCEPROP 2 LAST SEC_TYPE 0402LF
J 0
(-975 2150);
DISPLAY 1.021277 (-975 2150);
PAINT ORANGE (-975 2150);
DISPLAY INVISIBLE (-975 2150);
FORCEPROP 2 LAST REUSE_ID 26
J 0
(-975 2150);
DISPLAY 1.042553 (-975 2150);
PAINT ORANGE (-975 2150);
DISPLAY INVISIBLE (-975 2150);
FORCEPROP 2 LAST BOM_COST PVPP_KLM_VR
J 0
(-975 2100);
DISPLAY 1.042553 (-975 2100);
PAINT WHITE (-975 2100);
DISPLAY INVISIBLE (-975 2100);
FORCEPROP 0 LAST SPOF TRUE
J 0
(-975 2150);
DISPLAY 1.021277 (-975 2150);
PAINT ORANGE (-975 2150);
DISPLAY INVISIBLE (-975 2150);
FORCEADD RES..2
(-1025 2750);
FORCEPROP 1 LASTPIN (-1025 2850) $PN 1
J 0
(-1020 2812);
DISPLAY 0.617021 (-1020 2812);
PAINT ORANGE (-1020 2812);
FORCEPROP 1 LAST VALUE 1.0K
J 0
(-980 2825);
DISPLAY 0.617021 (-980 2825);
PAINT SKYBLUE (-980 2825);
FORCEPROP 1 LAST PART_NUMBER G85996-004
J 0
(-1010 2575);
DISPLAY 0.617021 (-1010 2575);
PAINT BLUE (-1010 2575);
FORCEPROP 1 LAST MATERIAL CHIP
J 0
(-985 2625);
DISPLAY 0.617021 (-985 2625);
PAINT SKYBLUE (-985 2625);
FORCEPROP 1 LASTPIN (-1025 2650) $PN 2
J 0
(-1020 2660);
DISPLAY 0.617021 (-1020 2660);
PAINT ORANGE (-1020 2660);
FORCEPROP 1 LAST PACK_TYPE 0402
J 0
(-985 2675);
DISPLAY 0.617021 (-985 2675);
PAINT SKYBLUE (-985 2675);
FORCEPROP 1 LAST WATTAGE 1/16W
J 0
(-985 2725);
DISPLAY 0.617021 (-985 2725);
PAINT SKYBLUE (-985 2725);
FORCEPROP 1 LAST TOLERANCE 0.1%
J 0
(-980 2775);
DISPLAY 0.617021 (-980 2775);
PAINT SKYBLUE (-980 2775);
FORCEPROP 1 LAST LOCATION R4B9
J 0
(-980 2875);
DISPLAY 0.617021 (-980 2875);
PAINT AQUA (-980 2875);
FORCEPROP 2 LAST CDS_LIB mstr_discrete
J 0
(-1025 2750);
PAINT MONO (-1025 2750);
DISPLAY INVISIBLE (-1025 2750);
FORCEPROP 2 LAST ROOM PVPP_KLM_VR
J 0
(-980 2905);
PAINT GREEN (-980 2905);
DISPLAY INVISIBLE (-980 2905);
FORCEPROP 1 LAST PATH I219
J 0
(-975 2925);
DISPLAY 0.978723 (-975 2925);
PAINT WHITE (-975 2925);
DISPLAY INVISIBLE (-975 2925);
FORCEPROP 2 LAST CDS_LOCATION R4B9
J 0
(-980 2875);
DISPLAY 0.617021 (-980 2875);
PAINT AQUA (-980 2875);
DISPLAY INVISIBLE (-980 2875);
FORCEPROP 2 LAST SEC 1
J 0
(-975 2975);
DISPLAY 0.680851 (-975 2975);
PAINT MONO (-975 2975);
DISPLAY INVISIBLE (-975 2975);
FORCEPROP 2 LAST SEC_TYPE 0402
J 0
(-975 2975);
DISPLAY 1.021277 (-975 2975);
PAINT ORANGE (-975 2975);
DISPLAY INVISIBLE (-975 2975);
FORCEPROP 2 LAST REUSE_ID 9
J 0
(-975 2975);
DISPLAY 1.042553 (-975 2975);
PAINT ORANGE (-975 2975);
DISPLAY INVISIBLE (-975 2975);
FORCEPROP 2 LAST BOM_COST PVPP_KLM_VR
J 0
(-980 2930);
DISPLAY 1.042553 (-980 2930);
PAINT WHITE (-980 2930);
DISPLAY INVISIBLE (-980 2930);
FORCEPROP 0 LAST SPOF TRUE
J 0
(-975 2975);
DISPLAY 1.021277 (-975 2975);
PAINT ORANGE (-975 2975);
DISPLAY INVISIBLE (-975 2975);
FORCEADD RES..1
(-5925 2825);
FORCEPROP 1 LAST PACK_TYPE 0402
J 0
(-5850 2725);
DISPLAY 0.617021 (-5850 2725);
PAINT SKYBLUE (-5850 2725);
FORCEPROP 1 LAST TOLERANCE 5%
J 0
(-5975 2725);
DISPLAY 0.617021 (-5975 2725);
PAINT SKYBLUE (-5975 2725);
FORCEPROP 1 LAST MATERIAL CHIP
J 0
(-5925 2675);
DISPLAY 0.617021 (-5925 2675);
PAINT SKYBLUE (-5925 2675);
FORCEPROP 1 LAST WATTAGE 1/16W
J 2
(-5950 2675);
DISPLAY 0.617021 (-5950 2675);
PAINT SKYBLUE (-5950 2675);
FORCEPROP 1 LAST PART_NUMBER G21497-005
J 0
(-6075 2775);
DISPLAY 0.617021 (-6075 2775);
PAINT BLUE (-6075 2775);
FORCEPROP 1 LASTPIN (-6025 2825) $PN 1
J 0
(-6013 2837);
DISPLAY 0.787234 (-6013 2837);
PAINT ORANGE (-6013 2837);
FORCEPROP 1 LASTPIN (-5825 2825) $PN 2
J 0
(-5863 2837);
DISPLAY 0.787234 (-5863 2837);
PAINT ORANGE (-5863 2837);
FORCEPROP 1 LAST LOCATION R4B1
J 0
(-5975 2875);
DISPLAY 0.617021 (-5975 2875);
PAINT AQUA (-5975 2875);
FORCEPROP 1 LAST VALUE 0.0
J 2
(-6025 2725);
DISPLAY 0.617021 (-6025 2725);
PAINT SKYBLUE (-6025 2725);
FORCEPROP 2 LAST SEC_TYPE 0402
J 0
(-5975 3025);
DISPLAY 1.021277 (-5975 3025);
PAINT ORANGE (-5975 3025);
DISPLAY INVISIBLE (-5975 3025);
FORCEPROP 2 LAST SEC 1
J 0
(-5975 3025);
PAINT MONO (-5975 3025);
DISPLAY INVISIBLE (-5975 3025);
FORCEPROP 2 LAST ROOM PVCCIN_CPU0_VR
J 0
(-5975 2925);
DISPLAY 1.361702 (-5975 2925);
PAINT ORANGE (-5975 2925);
DISPLAY INVISIBLE (-5975 2925);
FORCEPROP 1 LAST PATH I220
J 0
(-5975 2975);
DISPLAY 0.978723 (-5975 2975);
PAINT WHITE (-5975 2975);
DISPLAY INVISIBLE (-5975 2975);
FORCEPROP 2 LAST CDS_LOCATION R4B1
J 0
(-5975 2875);
DISPLAY 0.617021 (-5975 2875);
PAINT AQUA (-5975 2875);
DISPLAY INVISIBLE (-5975 2875);
FORCEPROP 2 LAST CDS_LIB mstr_discrete
J 0
(-5925 2825);
PAINT ORANGE (-5925 2825);
DISPLAY INVISIBLE (-5925 2825);
FORCEADD AGND_SCSI..1
(-1350 1050);
FORCEPROP 3 LASTPIN (-1350 1100) SIG_NAME AGND_PVPP_KLM\g
J 0
(-1340 1110);
DISPLAY 0.659574 (-1340 1110);
PAINT MONO (-1340 1110);
DISPLAY INVISIBLE (-1340 1110);
FORCEPROP 1 LAST HDL_POWER AGND_PVPP_KLM
J 1
(-1275 975);
DISPLAY 0.617021 (-1275 975);
PAINT GREEN (-1275 975);
FORCEPROP 1 LAST VOLTAGE 0.0V
J 0
(-1395 1007);
DISPLAY 0.340426 (-1395 1007);
PAINT SKYBLUE (-1395 1007);
DISPLAY INVISIBLE (-1395 1007);
FORCEPROP 2 LAST ROOM PVPP_KLM_VR
J 0
(-1500 1000);
DISPLAY 1.042553 (-1500 1000);
PAINT GREEN (-1500 1000);
DISPLAY INVISIBLE (-1500 1000);
FORCEPROP 1 LAST BODY_TYPE PLUMBING
J 0
(-1395 1007);
DISPLAY 0.340426 (-1395 1007);
PAINT GREEN (-1395 1007);
DISPLAY INVISIBLE (-1395 1007);
FORCEPROP 2 LAST CDS_LIB mstr_symbols
J 0
(-1350 1050);
PAINT ORANGE (-1350 1050);
DISPLAY INVISIBLE (-1350 1050);
FORCEPROP 2 LAST BOM_COST PVPP_KLM_VR
J 0
(-1500 1000);
DISPLAY 1.042553 (-1500 1000);
PAINT WHITE (-1500 1000);
DISPLAY INVISIBLE (-1500 1000);
FORCEPROP 1 LAST PATH I221
J 0
(-1275 1050);
DISPLAY 0.872340 (-1275 1050);
PAINT AQUA (-1275 1050);
DISPLAY INVISIBLE (-1275 1050);
FORCEADD SC22U16V5MX-4-GP..1
(-7050 4100);
FORCEPROP 2 LASTPIN (-7050 4025) $PN 2
R 1
J 2
(-7060 4015);
DISPLAY 0.808511 (-7060 4015);
PAINT ORANGE (-7060 4015);
FORCEPROP 2 LAST TYPE X6S
J 0
(-6950 4000);
DISPLAY 0.638298 (-6950 4000);
PAINT GREEN (-6950 4000);
FORCEPROP 2 LAST PACK_SIZE 0805
J 0
(-6950 3950);
DISPLAY 0.638298 (-6950 3950);
PAINT GREEN (-6950 3950);
FORCEPROP 2 LAST TOLERANCE 20%
J 0
(-6950 4100);
DISPLAY 0.638298 (-6950 4100);
PAINT GREEN (-6950 4100);
FORCEPROP 2 LAST RATED 16V
J 0
(-6950 4050);
DISPLAY 0.638298 (-6950 4050);
PAINT GREEN (-6950 4050);
FORCEPROP 1 LAST LOCATION C22W5
J 0
(-6950 4210);
DISPLAY 0.617021 (-6950 4210);
PAINT GREEN (-6950 4210);
FORCEPROP 2 LAST ATTRIBUTE 22UF
J 0
(-6950 4150);
DISPLAY 0.638298 (-6950 4150);
PAINT GREEN (-6950 4150);
FORCEPROP 2 LASTPIN (-7050 4175) $PN 1
R 1
J 0
(-7060 4185);
DISPLAY 0.808511 (-7060 4185);
PAINT ORANGE (-7060 4185);
FORCEPROP 1 LAST VALUE SC22U16V5MX-4-GP
R 1
J 0
(-6975 3895);
DISPLAY 0.617021 (-6975 3895);
PAINT GREEN (-6975 3895);
FORCEPROP 1 LAST PACK_TYPE SMD-BCG5
J 0
(-7050 4100);
DISPLAY 0.617021 (-7050 4100);
PAINT GREEN (-7050 4100);
DISPLAY INVISIBLE (-7050 4100);
FORCEPROP 2 LAST SEC 1
J 0
(-7025 4175);
DISPLAY 0.680851 (-7025 4175);
PAINT MONO (-7025 4175);
DISPLAY INVISIBLE (-7025 4175);
FORCEPROP 2 LAST SEC_TYPE SMD-BCG5
J 0
(-7025 4175);
DISPLAY 1.021277 (-7025 4175);
PAINT ORANGE (-7025 4175);
DISPLAY INVISIBLE (-7025 4175);
FORCEPROP 1 LAST PART_NUMBER 078.22611.0811
J 0
(-7050 4100);
DISPLAY 0.617021 (-7050 4100);
PAINT GREEN (-7050 4100);
DISPLAY INVISIBLE (-7050 4100);
FORCEPROP 2 LAST CDS_LIB w_hdl
J 0
(-7050 4100);
PAINT MONO (-7050 4100);
DISPLAY INVISIBLE (-7050 4100);
FORCEPROP 1 LAST CDS_LMAN_SYM_OUTLINE -50,25,50,-25
J 0
(-7050 4100);
DISPLAY 0.468085 (-7050 4100);
PAINT GREEN (-7050 4100);
DISPLAY INVISIBLE (-7050 4100);
FORCEPROP 1 LAST PATH I222
J 0
(-7050 4100);
DISPLAY 0.617021 (-7050 4100);
PAINT GREEN (-7050 4100);
DISPLAY INVISIBLE (-7050 4100);
FORCEADD SC22U16V5MX-4-GP..1
(-7350 4100);
FORCEPROP 2 LASTPIN (-7350 4025) $PN 2
R 1
J 2
(-7360 4015);
DISPLAY 0.808511 (-7360 4015);
PAINT ORANGE (-7360 4015);
FORCEPROP 2 LAST ATTRIBUTE 22UF
J 0
(-7250 4150);
DISPLAY 0.638298 (-7250 4150);
PAINT GREEN (-7250 4150);
FORCEPROP 2 LAST TOLERANCE 20%
J 0
(-7250 4100);
DISPLAY 0.638298 (-7250 4100);
PAINT GREEN (-7250 4100);
FORCEPROP 2 LAST RATED 16V
J 0
(-7250 4050);
DISPLAY 0.638298 (-7250 4050);
PAINT GREEN (-7250 4050);
FORCEPROP 2 LAST TYPE X6S
J 0
(-7250 4000);
DISPLAY 0.638298 (-7250 4000);
PAINT GREEN (-7250 4000);
FORCEPROP 2 LAST PACK_SIZE 0805
J 0
(-7250 3950);
DISPLAY 0.638298 (-7250 3950);
PAINT GREEN (-7250 3950);
FORCEPROP 2 LASTPIN (-7350 4175) $PN 1
R 1
J 0
(-7360 4185);
DISPLAY 0.808511 (-7360 4185);
PAINT ORANGE (-7360 4185);
FORCEPROP 1 LAST LOCATION C4B1
J 0
(-7250 4210);
DISPLAY 0.617021 (-7250 4210);
PAINT GREEN (-7250 4210);
FORCEPROP 1 LAST VALUE SC22U16V5MX-4-GP
R 1
J 0
(-7275 3895);
DISPLAY 0.617021 (-7275 3895);
PAINT GREEN (-7275 3895);
FORCEPROP 1 LAST CDS_LMAN_SYM_OUTLINE -50,25,50,-25
J 0
(-7350 4100);
DISPLAY 0.468085 (-7350 4100);
PAINT GREEN (-7350 4100);
DISPLAY INVISIBLE (-7350 4100);
FORCEPROP 2 LAST CDS_LIB w_hdl
J 0
(-7350 4100);
PAINT MONO (-7350 4100);
DISPLAY INVISIBLE (-7350 4100);
FORCEPROP 1 LAST PART_NUMBER 078.22611.0811
J 0
(-7350 4100);
DISPLAY 0.617021 (-7350 4100);
PAINT GREEN (-7350 4100);
DISPLAY INVISIBLE (-7350 4100);
FORCEPROP 2 LAST SEC_TYPE SMD-BCG5
J 0
(-7325 4175);
DISPLAY 1.021277 (-7325 4175);
PAINT ORANGE (-7325 4175);
DISPLAY INVISIBLE (-7325 4175);
FORCEPROP 2 LAST SEC 1
J 0
(-7325 4175);
DISPLAY 0.680851 (-7325 4175);
PAINT MONO (-7325 4175);
DISPLAY INVISIBLE (-7325 4175);
FORCEPROP 1 LAST PACK_TYPE SMD-BCG5
J 0
(-7350 4100);
DISPLAY 0.617021 (-7350 4100);
PAINT GREEN (-7350 4100);
DISPLAY INVISIBLE (-7350 4100);
FORCEPROP 1 LAST PATH I223
J 0
(-7350 4100);
DISPLAY 0.617021 (-7350 4100);
PAINT GREEN (-7350 4100);
DISPLAY INVISIBLE (-7350 4100);
FORCEADD GND..1
(-7350 3850);
FORCEPROP 3 LASTPIN (-7350 3900) SIG_NAME GND\g
J 0
(-7340 3910);
DISPLAY 0.659574 (-7340 3910);
PAINT MONO (-7340 3910);
DISPLAY INVISIBLE (-7340 3910);
FORCEPROP 1 LAST HDL_POWER GND
J 0
(-7350 4000);
DISPLAY 0.872340 (-7350 4000);
PAINT GREEN (-7350 4000);
DISPLAY INVISIBLE (-7350 4000);
FORCEPROP 1 LAST SIZE 1B
J 0
(-7275 3800);
DISPLAY 0.872340 (-7275 3800);
PAINT GREEN (-7275 3800);
DISPLAY INVISIBLE (-7275 3800);
FORCEPROP 1 LAST VOLTAGE 0
J 0
(-7350 3850);
PAINT SKYBLUE (-7350 3850);
DISPLAY INVISIBLE (-7350 3850);
FORCEPROP 1 LAST BODY_TYPE PLUMBING
J 0
(-7395 3807);
DISPLAY 0.340426 (-7395 3807);
PAINT GREEN (-7395 3807);
DISPLAY INVISIBLE (-7395 3807);
FORCEPROP 2 LAST ROOM PVPP_KLM_VR
J 0
(-7925 3925);
DISPLAY 1.042553 (-7925 3925);
PAINT GREEN (-7925 3925);
DISPLAY INVISIBLE (-7925 3925);
FORCEPROP 2 LAST BOM_COST PVPP_KLM_VR
J 0
(-8200 3925);
DISPLAY 1.042553 (-8200 3925);
PAINT WHITE (-8200 3925);
DISPLAY INVISIBLE (-8200 3925);
FORCEPROP 2 LAST CDS_LIB mstr_symbols
J 0
(-7350 3850);
PAINT MONO (-7350 3850);
DISPLAY INVISIBLE (-7350 3850);
FORCEPROP 1 LAST PATH I224
J 0
(-7275 3850);
DISPLAY 0.872340 (-7275 3850);
PAINT AQUA (-7275 3850);
DISPLAY INVISIBLE (-7275 3850);
FORCEADD GND..1
(-7050 3850);
FORCEPROP 3 LASTPIN (-7050 3900) SIG_NAME GND\g
J 0
(-7040 3910);
DISPLAY 0.659574 (-7040 3910);
PAINT MONO (-7040 3910);
DISPLAY INVISIBLE (-7040 3910);
FORCEPROP 1 LAST HDL_POWER GND
J 0
(-7050 4000);
DISPLAY 0.872340 (-7050 4000);
PAINT GREEN (-7050 4000);
DISPLAY INVISIBLE (-7050 4000);
FORCEPROP 1 LAST SIZE 1B
J 0
(-6975 3800);
DISPLAY 0.872340 (-6975 3800);
PAINT GREEN (-6975 3800);
DISPLAY INVISIBLE (-6975 3800);
FORCEPROP 1 LAST VOLTAGE 0
J 0
(-7050 3850);
PAINT SKYBLUE (-7050 3850);
DISPLAY INVISIBLE (-7050 3850);
FORCEPROP 1 LAST BODY_TYPE PLUMBING
J 0
(-7095 3807);
DISPLAY 0.340426 (-7095 3807);
PAINT GREEN (-7095 3807);
DISPLAY INVISIBLE (-7095 3807);
FORCEPROP 2 LAST ROOM PVPP_KLM_VR
J 0
(-7625 3925);
DISPLAY 1.042553 (-7625 3925);
PAINT GREEN (-7625 3925);
DISPLAY INVISIBLE (-7625 3925);
FORCEPROP 2 LAST BOM_COST PVPP_KLM_VR
J 0
(-7900 3925);
DISPLAY 1.042553 (-7900 3925);
PAINT WHITE (-7900 3925);
DISPLAY INVISIBLE (-7900 3925);
FORCEPROP 2 LAST CDS_LIB mstr_symbols
J 0
(-7050 3850);
PAINT MONO (-7050 3850);
DISPLAY INVISIBLE (-7050 3850);
FORCEPROP 1 LAST PATH I225
J 0
(-6975 3850);
DISPLAY 0.872340 (-6975 3850);
PAINT AQUA (-6975 3850);
DISPLAY INVISIBLE (-6975 3850);
FORCEADD RES..1
(-4150 4200);
FORCEPROP 1 LAST PACK_TYPE 0603
J 0
(-4275 4050);
DISPLAY 0.617021 (-4275 4050);
PAINT SKYBLUE (-4275 4050);
FORCEPROP 1 LAST TOLERANCE 5.0%
J 0
(-4200 4100);
DISPLAY 0.617021 (-4200 4100);
PAINT SKYBLUE (-4200 4100);
FORCEPROP 1 LAST PART_NUMBER G22178-002
J 0
(-4275 4150);
DISPLAY 0.617021 (-4275 4150);
PAINT BLUE (-4275 4150);
FORCEPROP 1 LASTPIN (-4250 4200) $PN 1
J 0
(-4238 4212);
DISPLAY 0.787234 (-4238 4212);
PAINT ORANGE (-4238 4212);
FORCEPROP 1 LASTPIN (-4050 4200) $PN 2
J 0
(-4088 4212);
DISPLAY 0.787234 (-4088 4212);
PAINT ORANGE (-4088 4212);
FORCEPROP 1 LAST VALUE 0
J 0
(-4275 4100);
DISPLAY 0.617021 (-4275 4100);
PAINT SKYBLUE (-4275 4100);
FORCEPROP 1 LAST WATTAGE 1/10W
J 0
(-4150 4050);
DISPLAY 0.617021 (-4150 4050);
PAINT SKYBLUE (-4150 4050);
FORCEPROP 1 LAST LOCATION R4B13
J 0
(-4250 4250);
DISPLAY 0.617021 (-4250 4250);
PAINT AQUA (-4250 4250);
FORCEPROP 1 LAST MATERIAL CHIP
J 0
(-4150 4050);
DISPLAY 0.617021 (-4150 4050);
PAINT SKYBLUE (-4150 4050);
DISPLAY INVISIBLE (-4150 4050);
FORCEPROP 0 LAST ROOM NIC_SPRV
J 0
(-4050 4325);
DISPLAY 1.021277 (-4050 4325);
PAINT ORANGE (-4050 4325);
DISPLAY INVISIBLE (-4050 4325);
FORCEPROP 0 LAST BOM_COST NT_GBE_BASE
J 0
(-4050 4425);
DISPLAY 1.021277 (-4050 4425);
PAINT ORANGE (-4050 4425);
DISPLAY INVISIBLE (-4050 4425);
FORCEPROP 2 LAST CDS_LIB mstr_discrete
J 0
(-4150 4200);
PAINT MONO (-4150 4200);
DISPLAY INVISIBLE (-4150 4200);
FORCEPROP 2 LAST SEC_TYPE 0603
J 0
(-4200 4400);
DISPLAY 1.021277 (-4200 4400);
PAINT ORANGE (-4200 4400);
DISPLAY INVISIBLE (-4200 4400);
FORCEPROP 0 LAST SEC 1
J 0
(-4400 4300);
DISPLAY 0.680851 (-4400 4300);
PAINT MONO (-4400 4300);
DISPLAY INVISIBLE (-4400 4300);
FORCEPROP 0 LAST CDS_SEC 1
J 0
(-4075 4200);
PAINT MONO (-4075 4200);
DISPLAY INVISIBLE (-4075 4200);
FORCEPROP 1 LAST PATH I226
J 0
(-4200 4350);
DISPLAY 0.978723 (-4200 4350);
PAINT WHITE (-4200 4350);
DISPLAY INVISIBLE (-4200 4350);
FORCEPROP 0 LAST CDS_LOCATION R4B13
J 0
(-4075 4200);
PAINT MONO (-4075 4200);
DISPLAY INVISIBLE (-4075 4200);
FORCEADD RES..2
(-1350 1450);
FORCEPROP 1 LAST PART_NUMBER G21796-161
J 0
(-1310 1325);
DISPLAY 0.617021 (-1310 1325);
PAINT BLUE (-1310 1325);
FORCEPROP 1 LASTPIN (-1350 1550) $PN 1
J 0
(-1345 1512);
DISPLAY 0.617021 (-1345 1512);
PAINT ORANGE (-1345 1512);
FORCEPROP 1 LAST VALUE 6.19K
J 0
(-1305 1525);
DISPLAY 0.617021 (-1305 1525);
PAINT SKYBLUE (-1305 1525);
FORCEPROP 1 LAST TOLERANCE 1%
J 0
(-1305 1475);
DISPLAY 0.617021 (-1305 1475);
PAINT SKYBLUE (-1305 1475);
FORCEPROP 1 LAST WATTAGE 1/16W
J 0
(-1310 1425);
DISPLAY 0.617021 (-1310 1425);
PAINT SKYBLUE (-1310 1425);
FORCEPROP 1 LAST LOCATION R4B4
J 0
(-1305 1575);
DISPLAY 0.617021 (-1305 1575);
PAINT AQUA (-1305 1575);
FORCEPROP 1 LAST MATERIAL CHIP
J 0
(-1310 1375);
DISPLAY 0.617021 (-1310 1375);
PAINT SKYBLUE (-1310 1375);
FORCEPROP 1 LAST PACK_TYPE 0402
J 0
(-1310 1275);
DISPLAY 0.617021 (-1310 1275);
PAINT SKYBLUE (-1310 1275);
FORCEPROP 1 LASTPIN (-1350 1350) $PN 2
J 0
(-1345 1360);
DISPLAY 0.617021 (-1345 1360);
PAINT ORANGE (-1345 1360);
FORCEPROP 0 LAST BOM_COST IO_SLOT
J 0
(-1300 1775);
DISPLAY 1.021277 (-1300 1775);
PAINT ORANGE (-1300 1775);
DISPLAY INVISIBLE (-1300 1775);
FORCEPROP 2 LAST SEC 1
J 0
(-1300 1675);
DISPLAY 0.680851 (-1300 1675);
PAINT MONO (-1300 1675);
DISPLAY INVISIBLE (-1300 1675);
FORCEPROP 2 LAST SEC_TYPE 0402
J 0
(-1300 1675);
DISPLAY 1.021277 (-1300 1675);
PAINT ORANGE (-1300 1675);
DISPLAY INVISIBLE (-1300 1675);
FORCEPROP 0 LAST ROOM IO_SLOT
J 0
(-1300 1675);
DISPLAY 1.021277 (-1300 1675);
PAINT ORANGE (-1300 1675);
DISPLAY INVISIBLE (-1300 1675);
FORCEPROP 2 LAST CDS_LIB mstr_discrete
J 0
(-1350 1450);
PAINT ORANGE (-1350 1450);
DISPLAY INVISIBLE (-1350 1450);
FORCEPROP 0 LAST CDS_SEC 1
J 0
(-1300 1625);
PAINT MONO (-1300 1625);
DISPLAY INVISIBLE (-1300 1625);
FORCEPROP 1 LAST PATH I227
J 0
(-1300 1625);
DISPLAY 0.978723 (-1300 1625);
PAINT WHITE (-1300 1625);
DISPLAY INVISIBLE (-1300 1625);
FORCEPROP 2 LAST CDS_LOCATION R4B4
J 0
(-1305 1575);
DISPLAY 0.617021 (-1305 1575);
PAINT AQUA (-1305 1575);
DISPLAY INVISIBLE (-1305 1575);
FORCEADD RES..2
R 2
(-4750 1650);
FORCEPROP 1 LAST MATERIAL CHIP
J 2
(-4790 1575);
DISPLAY 0.617021 (-4790 1575);
PAINT SKYBLUE (-4790 1575);
FORCEPROP 1 LAST PACK_TYPE 0402
J 2
(-4790 1475);
DISPLAY 0.617021 (-4790 1475);
PAINT SKYBLUE (-4790 1475);
FORCEPROP 1 LASTPIN (-4750 1750) $PN 1
J 2
(-4755 1712);
DISPLAY 0.617021 (-4755 1712);
PAINT WHITE (-4755 1712);
FORCEPROP 1 LASTPIN (-4750 1550) $PN 2
J 2
(-4755 1560);
DISPLAY 0.617021 (-4755 1560);
PAINT WHITE (-4755 1560);
FORCEPROP 1 LAST TOLERANCE 1.0%
J 2
(-4795 1675);
DISPLAY 0.617021 (-4795 1675);
PAINT SKYBLUE (-4795 1675);
FORCEPROP 1 LAST LOCATION R4B6
J 2
(-4795 1775);
DISPLAY 0.617021 (-4795 1775);
PAINT AQUA (-4795 1775);
FORCEPROP 1 LAST WATTAGE 1/16W
J 2
(-4790 1625);
DISPLAY 0.617021 (-4790 1625);
PAINT SKYBLUE (-4790 1625);
FORCEPROP 0 LAST CONFIG 64.39015.6DL
J 0
(-5150 1425);
DISPLAY 0.638298 (-5150 1425);
PAINT BROWN (-5150 1425);
DISPLAY BOTH (-5150 1425);
FORCEPROP 0 LAST NEW_VALUE 3.9K
J 0
(-5150 1375);
DISPLAY 0.638298 (-5150 1375);
PAINT BROWN (-5150 1375);
DISPLAY BOTH (-5150 1375);
FORCEPROP 2 LAST CDS_LOCATION R4B6
J 2
(-4795 1775);
DISPLAY 0.617021 (-4795 1775);
PAINT AQUA (-4795 1775);
DISPLAY INVISIBLE (-4795 1775);
FORCEPROP 2 LAST CDS_SEC 1
J 2
(-4650 2025);
DISPLAY 1.042553 (-4650 2025);
PAINT ORANGE (-4650 2025);
DISPLAY INVISIBLE (-4650 2025);
FORCEPROP 2 LAST $SEC 1
J 0
(-4800 1875);
DISPLAY 0.680851 (-4800 1875);
PAINT MONO (-4800 1875);
DISPLAY INVISIBLE (-4800 1875);
FORCEPROP 2 LAST CDS_LIB mstr_discrete
J 2
(-4750 1650);
PAINT MONO (-4750 1650);
DISPLAY INVISIBLE (-4750 1650);
FORCEPROP 2 LAST BOM_COST PVPP_KLM_VR
J 2
(-4750 1650);
PAINT WHITE (-4750 1650);
DISPLAY INVISIBLE (-4750 1650);
FORCEPROP 2 LAST ROOM PVPP_KLM_VR
J 2
(-4750 1650);
PAINT GREEN (-4750 1650);
DISPLAY INVISIBLE (-4750 1650);
FORCEPROP 1 LAST VALUE 7.87K
J 2
(-4795 1725);
DISPLAY 0.617021 (-4795 1725);
PAINT SKYBLUE (-4795 1725);
DISPLAY INVISIBLE (-4795 1725);
FORCEPROP 1 LAST PART_NUMBER G21796-242
J 2
(-4790 1525);
DISPLAY 0.617021 (-4790 1525);
PAINT BLUE (-4790 1525);
DISPLAY INVISIBLE (-4790 1525);
FORCEPROP 1 LAST PATH I228
J 2
(-4800 1825);
DISPLAY 0.978723 (-4800 1825);
PAINT WHITE (-4800 1825);
DISPLAY INVISIBLE (-4800 1825);
FORCEADD GND..1
(-1450 550);
FORCEPROP 3 LASTPIN (-1450 600) SIG_NAME GND\g
J 0
(-1440 610);
DISPLAY 0.659574 (-1440 610);
PAINT MONO (-1440 610);
DISPLAY INVISIBLE (-1440 610);
FORCEPROP 1 LAST VOLTAGE 0
J 0
(-1450 550);
PAINT SKYBLUE (-1450 550);
DISPLAY INVISIBLE (-1450 550);
FORCEPROP 2 LAST CDS_LIB mstr_symbols
J 0
(-1450 550);
PAINT MONO (-1450 550);
DISPLAY INVISIBLE (-1450 550);
FORCEPROP 1 LAST PATH I27
J 0
(-1375 550);
DISPLAY 0.872340 (-1375 550);
PAINT AQUA (-1375 550);
DISPLAY INVISIBLE (-1375 550);
FORCEPROP 1 LAST HDL_POWER GND
J 0
(-1450 700);
DISPLAY 0.872340 (-1450 700);
PAINT GREEN (-1450 700);
DISPLAY INVISIBLE (-1450 700);
FORCEPROP 1 LAST SIZE 1B
J 0
(-1375 500);
DISPLAY 0.872340 (-1375 500);
PAINT AQUA (-1375 500);
DISPLAY INVISIBLE (-1375 500);
FORCEPROP 1 LAST BODY_TYPE PLUMBING
J 0
(-1495 507);
DISPLAY 0.340426 (-1495 507);
PAINT GREEN (-1495 507);
DISPLAY INVISIBLE (-1495 507);
FORCEPROP 2 LAST ROOM PVPP_KLM_VR
J 0
(-2025 625);
DISPLAY 1.042553 (-2025 625);
PAINT GREEN (-2025 625);
DISPLAY INVISIBLE (-2025 625);
FORCEPROP 2 LAST BOM_COST PVPP_KLM_VR
J 0
(-2300 625);
DISPLAY 1.042553 (-2300 625);
PAINT WHITE (-2300 625);
DISPLAY INVISIBLE (-2300 625);
FORCEADD AGND_SCSI..1
(-900 550);
FORCEPROP 3 LASTPIN (-900 600) SIG_NAME AGND_PVPP_KLM\g
J 0
(-890 610);
DISPLAY 0.659574 (-890 610);
PAINT MONO (-890 610);
DISPLAY INVISIBLE (-890 610);
FORCEPROP 1 LAST HDL_POWER AGND_PVPP_KLM
J 1
(-825 475);
DISPLAY 0.617021 (-825 475);
PAINT GREEN (-825 475);
FORCEPROP 1 LAST PATH I28
J 0
(-825 550);
DISPLAY 0.872340 (-825 550);
PAINT AQUA (-825 550);
DISPLAY INVISIBLE (-825 550);
FORCEPROP 2 LAST CDS_LIB mstr_symbols
J 0
(-900 550);
PAINT ORANGE (-900 550);
DISPLAY INVISIBLE (-900 550);
FORCEPROP 1 LAST BODY_TYPE PLUMBING
J 0
(-945 507);
DISPLAY 0.340426 (-945 507);
PAINT GREEN (-945 507);
DISPLAY INVISIBLE (-945 507);
FORCEPROP 1 LAST VOLTAGE 0.0V
J 0
(-945 507);
DISPLAY 0.340426 (-945 507);
PAINT SKYBLUE (-945 507);
DISPLAY INVISIBLE (-945 507);
FORCEPROP 2 LAST BOM_COST PVPP_KLM_VR
J 0
(-1050 500);
DISPLAY 1.042553 (-1050 500);
PAINT WHITE (-1050 500);
DISPLAY INVISIBLE (-1050 500);
FORCEPROP 2 LAST ROOM PVPP_KLM_VR
J 0
(-1050 500);
DISPLAY 1.042553 (-1050 500);
PAINT GREEN (-1050 500);
DISPLAY INVISIBLE (-1050 500);
FORCEADD RES..1
(-1150 650);
FORCEPROP 1 LAST PART_NUMBER G21497-005
J 0
(-1275 600);
DISPLAY 0.617021 (-1275 600);
PAINT BLUE (-1275 600);
FORCEPROP 1 LAST VALUE 0.0
J 2
(-1175 550);
DISPLAY 0.617021 (-1175 550);
PAINT SKYBLUE (-1175 550);
FORCEPROP 1 LAST WATTAGE 1/16W
J 2
(-1150 500);
DISPLAY 0.617021 (-1150 500);
PAINT SKYBLUE (-1150 500);
FORCEPROP 1 LAST PACK_TYPE 0402
J 0
(-1225 450);
DISPLAY 0.617021 (-1225 450);
PAINT SKYBLUE (-1225 450);
FORCEPROP 1 LASTPIN (-1050 650) $PN 2
J 0
(-1088 662);
DISPLAY 0.617021 (-1088 662);
PAINT WHITE (-1088 662);
FORCEPROP 1 LAST TOLERANCE 5%
J 0
(-1150 550);
DISPLAY 0.617021 (-1150 550);
PAINT SKYBLUE (-1150 550);
FORCEPROP 1 LAST LOCATION R4B14
J 0
(-1200 700);
DISPLAY 0.617021 (-1200 700);
PAINT AQUA (-1200 700);
FORCEPROP 1 LASTPIN (-1250 650) $PN 1
J 0
(-1238 662);
DISPLAY 0.617021 (-1238 662);
PAINT WHITE (-1238 662);
FORCEPROP 1 LAST MATERIAL CHIP
J 0
(-1150 500);
DISPLAY 0.617021 (-1150 500);
PAINT SKYBLUE (-1150 500);
FORCEPROP 1 LAST PATH I29
J 0
(-1200 800);
DISPLAY 0.978723 (-1200 800);
PAINT WHITE (-1200 800);
DISPLAY INVISIBLE (-1200 800);
FORCEPROP 2 LAST $SEC 1
J 0
(-1185 855);
PAINT MONO (-1185 855);
DISPLAY INVISIBLE (-1185 855);
FORCEPROP 2 LAST CDS_SEC 1
J 0
(-1190 835);
PAINT MONO (-1190 835);
DISPLAY INVISIBLE (-1190 835);
FORCEPROP 2 LAST CDS_LIB mstr_discrete
J 0
(-1150 650);
PAINT MONO (-1150 650);
DISPLAY INVISIBLE (-1150 650);
FORCEPROP 2 LAST ROOM PVPP_KLM_VR
J 0
(-1200 725);
PAINT GREEN (-1200 725);
DISPLAY INVISIBLE (-1200 725);
FORCEADD CAP..1
(-5125 725);
FORCEPROP 1 LAST PACK_TYPE 0603LF
J 0
(-5075 525);
DISPLAY 0.617021 (-5075 525);
PAINT SKYBLUE (-5075 525);
FORCEPROP 1 LASTPIN (-5125 825) $PN 1
J 0
(-5115 805);
DISPLAY 0.617021 (-5115 805);
PAINT GREEN (-5115 805);
FORCEPROP 1 LASTPIN (-5125 625) $PN 2
J 0
(-5115 605);
DISPLAY 0.617021 (-5115 605);
PAINT GREEN (-5115 605);
FORCEPROP 1 LAST MATERIAL X6S
J 0
(-5075 625);
DISPLAY 0.617021 (-5075 625);
PAINT SKYBLUE (-5075 625);
FORCEPROP 1 LAST PART_NUMBER E15431-001
J 0
(-5075 575);
DISPLAY 0.617021 (-5075 575);
PAINT BLUE (-5075 575);
FORCEPROP 1 LAST VOLTAGE 4V
J 0
(-5075 725);
DISPLAY 0.638298 (-5075 725);
PAINT SKYBLUE (-5075 725);
FORCEPROP 1 LAST VALUE 10UF
J 0
(-5075 775);
DISPLAY 0.617021 (-5075 775);
PAINT SKYBLUE (-5075 775);
FORCEPROP 1 LAST LOCATION C3B2
J 0
(-5075 825);
DISPLAY 0.617021 (-5075 825);
PAINT AQUA (-5075 825);
FORCEPROP 0 LAST GROUP PWR_MLCC_CAP
J 0
(-5069 412);
DISPLAY 0.638298 (-5069 412);
PAINT BROWN (-5069 412);
DISPLAY BOTH (-5069 412);
FORCEPROP 1 LAST TOLERANCE 20%
J 0
(-5075 675);
DISPLAY 0.617021 (-5075 675);
PAINT SKYBLUE (-5075 675);
FORCEPROP 2 LAST CDS_LIB mstr_discrete
J 0
(-5125 725);
PAINT MONO (-5125 725);
DISPLAY INVISIBLE (-5125 725);
FORCEPROP 2 LAST ROOM PVPP_KLM_VR
J 0
(-5075 875);
PAINT MONO (-5075 875);
DISPLAY INVISIBLE (-5075 875);
FORCEPROP 1 LAST PATH I84
J 0
(-5075 875);
DISPLAY 0.978723 (-5075 875);
PAINT WHITE (-5075 875);
DISPLAY INVISIBLE (-5075 875);
FORCEPROP 2 LAST CDS_LOCATION C3B2
J 0
(-5075 825);
DISPLAY 0.617021 (-5075 825);
PAINT AQUA (-5075 825);
DISPLAY INVISIBLE (-5075 825);
FORCEPROP 2 LAST SEC 1
J 0
(-5055 945);
DISPLAY 0.680851 (-5055 945);
PAINT MONO (-5055 945);
DISPLAY INVISIBLE (-5055 945);
FORCEPROP 2 LAST SEC_TYPE 0603LF
J 0
(-5055 945);
DISPLAY 1.021277 (-5055 945);
PAINT ORANGE (-5055 945);
DISPLAY INVISIBLE (-5055 945);
FORCEPROP 2 LAST BOM_COST MEM_VRD_PVPP_AB
J 0
(-5075 875);
PAINT MONO (-5075 875);
DISPLAY INVISIBLE (-5075 875);
FORCEADD GND..1
(-8225 275);
FORCEPROP 3 LASTPIN (-8225 325) SIG_NAME GND\g
J 0
(-8215 335);
DISPLAY 0.659574 (-8215 335);
PAINT MONO (-8215 335);
DISPLAY INVISIBLE (-8215 335);
FORCEPROP 2 LAST ROOM PVPP_KLM_VR
J 0
(-8775 350);
PAINT ORANGE (-8775 350);
DISPLAY INVISIBLE (-8775 350);
FORCEPROP 1 LAST BODY_TYPE PLUMBING
J 0
(-8270 232);
DISPLAY 0.340426 (-8270 232);
PAINT GREEN (-8270 232);
DISPLAY INVISIBLE (-8270 232);
FORCEPROP 1 LAST SIZE 1B
J 0
(-8150 225);
DISPLAY 0.893617 (-8150 225);
PAINT GREEN (-8150 225);
DISPLAY INVISIBLE (-8150 225);
FORCEPROP 2 LAST CDS_LIB mstr_symbols
J 0
(-8225 275);
PAINT MONO (-8225 275);
DISPLAY INVISIBLE (-8225 275);
FORCEPROP 1 LAST VOLTAGE 0
J 0
(-8225 275);
PAINT SKYBLUE (-8225 275);
DISPLAY INVISIBLE (-8225 275);
FORCEPROP 1 LAST PATH I85
J 0
(-8150 275);
DISPLAY 0.872340 (-8150 275);
PAINT AQUA (-8150 275);
DISPLAY INVISIBLE (-8150 275);
FORCEPROP 2 LAST BOM_COST MEM_VRD_PVPP_AB
J 0
(-8550 350);
PAINT MONO (-8550 350);
DISPLAY INVISIBLE (-8550 350);
FORCEPROP 1 LAST HDL_POWER GND
J 0
(-8225 425);
DISPLAY 0.893617 (-8225 425);
PAINT GREEN (-8225 425);
DISPLAY INVISIBLE (-8225 425);
FORCEADD CAP..1
(-5400 700);
FORCEPROP 1 LAST VALUE 10UF
J 0
(-5350 750);
DISPLAY 0.617021 (-5350 750);
PAINT SKYBLUE (-5350 750);
FORCEPROP 1 LAST VOLTAGE 4V
J 0
(-5350 700);
DISPLAY 0.638298 (-5350 700);
PAINT SKYBLUE (-5350 700);
FORCEPROP 1 LAST PART_NUMBER E15431-001
J 0
(-5350 550);
DISPLAY 0.617021 (-5350 550);
PAINT BLUE (-5350 550);
FORCEPROP 1 LAST LOCATION C3A8
J 0
(-5350 800);
DISPLAY 0.617021 (-5350 800);
PAINT AQUA (-5350 800);
FORCEPROP 1 LAST MATERIAL X6S
J 0
(-5350 600);
DISPLAY 0.617021 (-5350 600);
PAINT SKYBLUE (-5350 600);
FORCEPROP 1 LAST TOLERANCE 20%
J 0
(-5350 650);
DISPLAY 0.617021 (-5350 650);
PAINT SKYBLUE (-5350 650);
FORCEPROP 1 LASTPIN (-5400 600) $PN 2
J 0
(-5390 580);
DISPLAY 0.617021 (-5390 580);
PAINT GREEN (-5390 580);
FORCEPROP 1 LASTPIN (-5400 800) $PN 1
J 0
(-5390 780);
DISPLAY 0.617021 (-5390 780);
PAINT GREEN (-5390 780);
FORCEPROP 1 LAST PACK_TYPE 0603LF
J 0
(-5350 500);
DISPLAY 0.617021 (-5350 500);
PAINT SKYBLUE (-5350 500);
FORCEPROP 0 LAST GROUP PWR_MLCC_CAP
J 0
(-5344 462);
DISPLAY 0.638298 (-5344 462);
PAINT BROWN (-5344 462);
DISPLAY BOTH (-5344 462);
FORCEPROP 2 LAST ROOM PVPP_KLM_VR
J 0
(-5350 850);
PAINT MONO (-5350 850);
DISPLAY INVISIBLE (-5350 850);
FORCEPROP 1 LAST PATH I86
J 0
(-5350 850);
DISPLAY 0.978723 (-5350 850);
PAINT WHITE (-5350 850);
DISPLAY INVISIBLE (-5350 850);
FORCEPROP 2 LAST CDS_LOCATION C3A8
J 0
(-5350 800);
DISPLAY 0.617021 (-5350 800);
PAINT AQUA (-5350 800);
DISPLAY INVISIBLE (-5350 800);
FORCEPROP 2 LAST $SEC 1
J 0
(-5350 900);
PAINT MONO (-5350 900);
DISPLAY INVISIBLE (-5350 900);
FORCEPROP 2 LAST CDS_SEC 1
J 0
(-5350 900);
PAINT MONO (-5350 900);
DISPLAY INVISIBLE (-5350 900);
FORCEPROP 2 LAST BOM_COST MEM_VRD_PVPP_AB
J 0
(-5350 850);
PAINT MONO (-5350 850);
DISPLAY INVISIBLE (-5350 850);
FORCEPROP 2 LAST CDS_LIB mstr_discrete
J 0
(-5400 700);
PAINT MONO (-5400 700);
DISPLAY INVISIBLE (-5400 700);
FORCEADD CAP..1
(-5675 700);
FORCEPROP 1 LAST LOCATION C7L3
J 0
(-5625 800);
DISPLAY 0.617021 (-5625 800);
PAINT AQUA (-5625 800);
FORCEPROP 1 LAST MATERIAL X6S
J 0
(-5625 600);
DISPLAY 0.617021 (-5625 600);
PAINT SKYBLUE (-5625 600);
FORCEPROP 1 LAST PACK_TYPE 0603LF
J 0
(-5625 500);
DISPLAY 0.617021 (-5625 500);
PAINT SKYBLUE (-5625 500);
FORCEPROP 1 LASTPIN (-5675 800) $PN 1
J 0
(-5665 780);
DISPLAY 0.617021 (-5665 780);
PAINT GREEN (-5665 780);
FORCEPROP 1 LASTPIN (-5675 600) $PN 2
J 0
(-5665 580);
DISPLAY 0.617021 (-5665 580);
PAINT GREEN (-5665 580);
FORCEPROP 1 LAST VALUE 10UF
J 0
(-5625 750);
DISPLAY 0.617021 (-5625 750);
PAINT SKYBLUE (-5625 750);
FORCEPROP 1 LAST VOLTAGE 4V
J 0
(-5625 700);
DISPLAY 0.638298 (-5625 700);
PAINT SKYBLUE (-5625 700);
FORCEPROP 1 LAST TOLERANCE 20%
J 0
(-5625 650);
DISPLAY 0.617021 (-5625 650);
PAINT SKYBLUE (-5625 650);
FORCEPROP 1 LAST PART_NUMBER E15431-001
J 0
(-5625 550);
DISPLAY 0.617021 (-5625 550);
PAINT BLUE (-5625 550);
FORCEPROP 0 LAST GROUP PWR_MLCC_CAP
J 0
(-5619 412);
DISPLAY 0.638298 (-5619 412);
PAINT BROWN (-5619 412);
DISPLAY BOTH (-5619 412);
FORCEPROP 2 LAST CDS_SEC 1
J 0
(-5625 900);
PAINT MONO (-5625 900);
DISPLAY INVISIBLE (-5625 900);
FORCEPROP 2 LAST BOM_COST MEM_VRD_PVPP_AB
J 0
(-5625 850);
PAINT MONO (-5625 850);
DISPLAY INVISIBLE (-5625 850);
FORCEPROP 2 LAST $SEC 1
J 0
(-5625 900);
PAINT MONO (-5625 900);
DISPLAY INVISIBLE (-5625 900);
FORCEPROP 2 LAST CDS_LOCATION C7L3
J 0
(-5625 800);
DISPLAY 0.617021 (-5625 800);
PAINT AQUA (-5625 800);
DISPLAY INVISIBLE (-5625 800);
FORCEPROP 1 LAST PATH I87
J 0
(-5625 850);
DISPLAY 0.978723 (-5625 850);
PAINT WHITE (-5625 850);
DISPLAY INVISIBLE (-5625 850);
FORCEPROP 2 LAST ROOM PVPP_KLM_VR
J 0
(-5625 850);
PAINT MONO (-5625 850);
DISPLAY INVISIBLE (-5625 850);
FORCEPROP 2 LAST CDS_LIB mstr_discrete
J 0
(-5675 700);
PAINT MONO (-5675 700);
DISPLAY INVISIBLE (-5675 700);
FORCEADD CAP..1
(-5950 725);
FORCEPROP 1 LAST VOLTAGE 4V
J 0
(-5900 725);
DISPLAY 0.638298 (-5900 725);
PAINT SKYBLUE (-5900 725);
FORCEPROP 1 LAST PART_NUMBER E15431-001
J 0
(-5900 575);
DISPLAY 0.617021 (-5900 575);
PAINT BLUE (-5900 575);
FORCEPROP 1 LAST VALUE 10UF
J 0
(-5900 775);
DISPLAY 0.617021 (-5900 775);
PAINT SKYBLUE (-5900 775);
FORCEPROP 1 LAST TOLERANCE 20%
J 0
(-5900 675);
DISPLAY 0.617021 (-5900 675);
PAINT SKYBLUE (-5900 675);
FORCEPROP 1 LAST MATERIAL X6S
J 0
(-5900 625);
DISPLAY 0.617021 (-5900 625);
PAINT SKYBLUE (-5900 625);
FORCEPROP 1 LASTPIN (-5950 625) $PN 2
J 0
(-5940 605);
DISPLAY 0.617021 (-5940 605);
PAINT GREEN (-5940 605);
FORCEPROP 1 LAST PACK_TYPE 0603LF
J 0
(-5900 525);
DISPLAY 0.617021 (-5900 525);
PAINT SKYBLUE (-5900 525);
FORCEPROP 1 LASTPIN (-5950 825) $PN 1
J 0
(-5940 805);
DISPLAY 0.617021 (-5940 805);
PAINT GREEN (-5940 805);
FORCEPROP 1 LAST LOCATION C7L2
J 0
(-5900 825);
DISPLAY 0.617021 (-5900 825);
PAINT AQUA (-5900 825);
FORCEPROP 0 LAST GROUP PWR_MLCC_CAP
J 0
(-5894 462);
DISPLAY 0.638298 (-5894 462);
PAINT BROWN (-5894 462);
DISPLAY BOTH (-5894 462);
FORCEPROP 2 LAST CDS_SEC 1
J 0
(-5900 925);
PAINT MONO (-5900 925);
DISPLAY INVISIBLE (-5900 925);
FORCEPROP 2 LAST $SEC 1
J 0
(-5900 925);
PAINT MONO (-5900 925);
DISPLAY INVISIBLE (-5900 925);
FORCEPROP 1 LAST PATH I88
J 0
(-5900 875);
DISPLAY 0.978723 (-5900 875);
PAINT WHITE (-5900 875);
DISPLAY INVISIBLE (-5900 875);
FORCEPROP 2 LAST BOM_COST MEM_VRD_PVPP_AB
J 0
(-5900 875);
PAINT MONO (-5900 875);
DISPLAY INVISIBLE (-5900 875);
FORCEPROP 2 LAST ROOM PVPP_KLM_VR
J 0
(-5900 875);
PAINT MONO (-5900 875);
DISPLAY INVISIBLE (-5900 875);
FORCEPROP 2 LAST CDS_LOCATION C7L2
J 0
(-5900 825);
DISPLAY 0.617021 (-5900 825);
PAINT AQUA (-5900 825);
DISPLAY INVISIBLE (-5900 825);
FORCEPROP 2 LAST CDS_LIB mstr_discrete
J 0
(-5950 725);
PAINT MONO (-5950 725);
DISPLAY INVISIBLE (-5950 725);
FORCEADD CAP..1
(-6250 725);
FORCEPROP 1 LAST VOLTAGE 4V
J 0
(-6200 725);
DISPLAY 0.638298 (-6200 725);
PAINT SKYBLUE (-6200 725);
FORCEPROP 1 LAST LOCATION C7L7
J 0
(-6200 825);
DISPLAY 0.617021 (-6200 825);
PAINT AQUA (-6200 825);
FORCEPROP 1 LAST VALUE 10UF
J 0
(-6200 775);
DISPLAY 0.617021 (-6200 775);
PAINT SKYBLUE (-6200 775);
FORCEPROP 1 LASTPIN (-6250 825) $PN 1
J 0
(-6240 805);
DISPLAY 0.617021 (-6240 805);
PAINT GREEN (-6240 805);
FORCEPROP 1 LASTPIN (-6250 625) $PN 2
J 0
(-6240 605);
DISPLAY 0.617021 (-6240 605);
PAINT GREEN (-6240 605);
FORCEPROP 1 LAST PACK_TYPE 0603LF
J 0
(-6200 525);
DISPLAY 0.617021 (-6200 525);
PAINT SKYBLUE (-6200 525);
FORCEPROP 1 LAST PART_NUMBER E15431-001
J 0
(-6200 575);
DISPLAY 0.617021 (-6200 575);
PAINT BLUE (-6200 575);
FORCEPROP 1 LAST MATERIAL X6S
J 0
(-6200 625);
DISPLAY 0.617021 (-6200 625);
PAINT SKYBLUE (-6200 625);
FORCEPROP 1 LAST TOLERANCE 20%
J 0
(-6200 675);
DISPLAY 0.617021 (-6200 675);
PAINT SKYBLUE (-6200 675);
FORCEPROP 0 LAST GROUP PWR_MLCC_CAP
J 0
(-6194 412);
DISPLAY 0.638298 (-6194 412);
PAINT BROWN (-6194 412);
DISPLAY BOTH (-6194 412);
FORCEPROP 2 LAST CDS_SEC 1
J 0
(-6200 925);
PAINT MONO (-6200 925);
DISPLAY INVISIBLE (-6200 925);
FORCEPROP 2 LAST $SEC 1
J 0
(-6200 925);
PAINT MONO (-6200 925);
DISPLAY INVISIBLE (-6200 925);
FORCEPROP 1 LAST PATH I89
J 0
(-6200 875);
DISPLAY 0.978723 (-6200 875);
PAINT WHITE (-6200 875);
DISPLAY INVISIBLE (-6200 875);
FORCEPROP 2 LAST BOM_COST MEM_VRD_PVPP_AB
J 0
(-6200 875);
PAINT MONO (-6200 875);
DISPLAY INVISIBLE (-6200 875);
FORCEPROP 2 LAST ROOM PVPP_KLM_VR
J 0
(-6200 875);
PAINT MONO (-6200 875);
DISPLAY INVISIBLE (-6200 875);
FORCEPROP 2 LAST CDS_LOCATION C7L7
J 0
(-6200 825);
DISPLAY 0.617021 (-6200 825);
PAINT AQUA (-6200 825);
DISPLAY INVISIBLE (-6200 825);
FORCEPROP 2 LAST CDS_LIB mstr_discrete
J 0
(-6250 725);
PAINT MONO (-6250 725);
DISPLAY INVISIBLE (-6250 725);
FORCEADD CAP..1
(-6550 725);
FORCEPROP 1 LAST VOLTAGE 4V
J 0
(-6500 725);
DISPLAY 0.638298 (-6500 725);
PAINT SKYBLUE (-6500 725);
FORCEPROP 1 LAST LOCATION C7L6
J 0
(-6500 825);
DISPLAY 0.617021 (-6500 825);
PAINT AQUA (-6500 825);
FORCEPROP 1 LAST VALUE 10UF
J 0
(-6500 775);
DISPLAY 0.617021 (-6500 775);
PAINT SKYBLUE (-6500 775);
FORCEPROP 1 LASTPIN (-6550 825) $PN 1
J 0
(-6540 805);
DISPLAY 0.617021 (-6540 805);
PAINT GREEN (-6540 805);
FORCEPROP 1 LAST TOLERANCE 20%
J 0
(-6500 675);
DISPLAY 0.617021 (-6500 675);
PAINT SKYBLUE (-6500 675);
FORCEPROP 1 LAST MATERIAL X6S
J 0
(-6500 625);
DISPLAY 0.617021 (-6500 625);
PAINT SKYBLUE (-6500 625);
FORCEPROP 1 LASTPIN (-6550 625) $PN 2
J 0
(-6540 605);
DISPLAY 0.617021 (-6540 605);
PAINT GREEN (-6540 605);
FORCEPROP 1 LAST PACK_TYPE 0603LF
J 0
(-6500 525);
DISPLAY 0.617021 (-6500 525);
PAINT SKYBLUE (-6500 525);
FORCEPROP 1 LAST PART_NUMBER E15431-001
J 0
(-6500 575);
DISPLAY 0.617021 (-6500 575);
PAINT BLUE (-6500 575);
FORCEPROP 0 LAST GROUP PWR_MLCC_CAP
J 0
(-6494 462);
DISPLAY 0.638298 (-6494 462);
PAINT BROWN (-6494 462);
DISPLAY BOTH (-6494 462);
FORCEPROP 2 LAST BOM_COST MEM_VRD_PVPP_AB
J 0
(-6500 875);
PAINT MONO (-6500 875);
DISPLAY INVISIBLE (-6500 875);
FORCEPROP 2 LAST CDS_SEC 1
J 0
(-6500 925);
PAINT MONO (-6500 925);
DISPLAY INVISIBLE (-6500 925);
FORCEPROP 2 LAST $SEC 1
J 0
(-6500 925);
PAINT MONO (-6500 925);
DISPLAY INVISIBLE (-6500 925);
FORCEPROP 2 LAST CDS_LOCATION C7L6
J 0
(-6500 825);
DISPLAY 0.617021 (-6500 825);
PAINT AQUA (-6500 825);
DISPLAY INVISIBLE (-6500 825);
FORCEPROP 1 LAST PATH I90
J 0
(-6500 875);
DISPLAY 0.978723 (-6500 875);
PAINT WHITE (-6500 875);
DISPLAY INVISIBLE (-6500 875);
FORCEPROP 2 LAST ROOM PVPP_KLM_VR
J 0
(-6500 875);
PAINT MONO (-6500 875);
DISPLAY INVISIBLE (-6500 875);
FORCEPROP 2 LAST CDS_LIB mstr_discrete
J 0
(-6550 725);
PAINT MONO (-6550 725);
DISPLAY INVISIBLE (-6550 725);
FORCEADD CAP..1
(-6825 725);
FORCEPROP 1 LAST VOLTAGE 4V
J 0
(-6775 725);
DISPLAY 0.638298 (-6775 725);
PAINT SKYBLUE (-6775 725);
FORCEPROP 1 LAST PART_NUMBER E15431-001
J 0
(-6775 575);
DISPLAY 0.617021 (-6775 575);
PAINT BLUE (-6775 575);
FORCEPROP 1 LAST VALUE 10UF
J 0
(-6775 775);
DISPLAY 0.617021 (-6775 775);
PAINT SKYBLUE (-6775 775);
FORCEPROP 1 LAST LOCATION C7M4
J 0
(-6775 825);
DISPLAY 0.617021 (-6775 825);
PAINT AQUA (-6775 825);
FORCEPROP 1 LASTPIN (-6825 825) $PN 1
J 0
(-6815 805);
DISPLAY 0.617021 (-6815 805);
PAINT GREEN (-6815 805);
FORCEPROP 1 LAST TOLERANCE 20%
J 0
(-6775 675);
DISPLAY 0.617021 (-6775 675);
PAINT SKYBLUE (-6775 675);
FORCEPROP 1 LAST MATERIAL X6S
J 0
(-6775 625);
DISPLAY 0.617021 (-6775 625);
PAINT SKYBLUE (-6775 625);
FORCEPROP 1 LASTPIN (-6825 625) $PN 2
J 0
(-6815 605);
DISPLAY 0.617021 (-6815 605);
PAINT GREEN (-6815 605);
FORCEPROP 1 LAST PACK_TYPE 0603LF
J 0
(-6775 525);
DISPLAY 0.617021 (-6775 525);
PAINT SKYBLUE (-6775 525);
FORCEPROP 0 LAST GROUP PWR_MLCC_CAP
J 0
(-6769 412);
DISPLAY 0.638298 (-6769 412);
PAINT BROWN (-6769 412);
DISPLAY BOTH (-6769 412);
FORCEPROP 2 LAST BOM_COST MEM_VRD_PVPP_AB
J 0
(-6775 875);
PAINT MONO (-6775 875);
DISPLAY INVISIBLE (-6775 875);
FORCEPROP 2 LAST CDS_SEC 1
J 0
(-6775 925);
PAINT MONO (-6775 925);
DISPLAY INVISIBLE (-6775 925);
FORCEPROP 2 LAST $SEC 1
J 0
(-6775 925);
PAINT MONO (-6775 925);
DISPLAY INVISIBLE (-6775 925);
FORCEPROP 2 LAST CDS_LOCATION C7M4
J 0
(-6775 825);
DISPLAY 0.617021 (-6775 825);
PAINT AQUA (-6775 825);
DISPLAY INVISIBLE (-6775 825);
FORCEPROP 1 LAST PATH I91
J 0
(-6775 875);
DISPLAY 0.978723 (-6775 875);
PAINT WHITE (-6775 875);
DISPLAY INVISIBLE (-6775 875);
FORCEPROP 2 LAST ROOM PVPP_KLM_VR
J 0
(-6775 875);
PAINT MONO (-6775 875);
DISPLAY INVISIBLE (-6775 875);
FORCEPROP 2 LAST CDS_LIB mstr_discrete
J 0
(-6825 725);
PAINT ORANGE (-6825 725);
DISPLAY INVISIBLE (-6825 725);
FORCEADD CAP..1
(-7125 725);
FORCEPROP 1 LAST VOLTAGE 4V
J 0
(-7075 725);
DISPLAY 0.638298 (-7075 725);
PAINT SKYBLUE (-7075 725);
FORCEPROP 1 LAST PART_NUMBER E15431-001
J 0
(-7075 575);
DISPLAY 0.617021 (-7075 575);
PAINT BLUE (-7075 575);
FORCEPROP 1 LAST PACK_TYPE 0603LF
J 0
(-7075 525);
DISPLAY 0.617021 (-7075 525);
PAINT SKYBLUE (-7075 525);
FORCEPROP 1 LAST VALUE 10UF
J 0
(-7075 775);
DISPLAY 0.617021 (-7075 775);
PAINT SKYBLUE (-7075 775);
FORCEPROP 1 LAST LOCATION C7M3
J 0
(-7075 825);
DISPLAY 0.617021 (-7075 825);
PAINT AQUA (-7075 825);
FORCEPROP 1 LASTPIN (-7125 825) $PN 1
J 0
(-7115 805);
DISPLAY 0.617021 (-7115 805);
PAINT GREEN (-7115 805);
FORCEPROP 1 LAST TOLERANCE 20%
J 0
(-7075 675);
DISPLAY 0.617021 (-7075 675);
PAINT SKYBLUE (-7075 675);
FORCEPROP 1 LAST MATERIAL X6S
J 0
(-7075 625);
DISPLAY 0.617021 (-7075 625);
PAINT SKYBLUE (-7075 625);
FORCEPROP 1 LASTPIN (-7125 625) $PN 2
J 0
(-7115 605);
DISPLAY 0.617021 (-7115 605);
PAINT GREEN (-7115 605);
FORCEPROP 0 LAST GROUP PWR_MLCC_CAP
J 0
(-7069 462);
DISPLAY 0.638298 (-7069 462);
PAINT BROWN (-7069 462);
DISPLAY BOTH (-7069 462);
FORCEPROP 2 LAST $SEC 1
J 0
(-7075 925);
PAINT MONO (-7075 925);
DISPLAY INVISIBLE (-7075 925);
FORCEPROP 2 LAST CDS_SEC 1
J 0
(-7075 925);
PAINT MONO (-7075 925);
DISPLAY INVISIBLE (-7075 925);
FORCEPROP 2 LAST ROOM PVPP_KLM_VR
J 0
(-7075 875);
PAINT MONO (-7075 875);
DISPLAY INVISIBLE (-7075 875);
FORCEPROP 1 LAST PATH I92
J 0
(-7075 875);
DISPLAY 0.978723 (-7075 875);
PAINT WHITE (-7075 875);
DISPLAY INVISIBLE (-7075 875);
FORCEPROP 2 LAST BOM_COST MEM_VRD_PVPP_AB
J 0
(-7075 875);
PAINT MONO (-7075 875);
DISPLAY INVISIBLE (-7075 875);
FORCEPROP 2 LAST CDS_LOCATION C7M3
J 0
(-7075 825);
DISPLAY 0.617021 (-7075 825);
PAINT AQUA (-7075 825);
DISPLAY INVISIBLE (-7075 825);
FORCEPROP 2 LAST CDS_LIB mstr_discrete
J 0
(-7125 725);
PAINT ORANGE (-7125 725);
DISPLAY INVISIBLE (-7125 725);
FORCEADD CAP..1
(-7400 700);
FORCEPROP 1 LAST VOLTAGE 4V
J 0
(-7350 700);
DISPLAY 0.638298 (-7350 700);
PAINT SKYBLUE (-7350 700);
FORCEPROP 1 LAST PACK_TYPE 0603LF
J 0
(-7350 500);
DISPLAY 0.617021 (-7350 500);
PAINT SKYBLUE (-7350 500);
FORCEPROP 1 LAST PART_NUMBER E15431-001
J 0
(-7350 550);
DISPLAY 0.617021 (-7350 550);
PAINT BLUE (-7350 550);
FORCEPROP 1 LAST LOCATION C3A4
J 0
(-7350 800);
DISPLAY 0.617021 (-7350 800);
PAINT AQUA (-7350 800);
FORCEPROP 1 LASTPIN (-7400 800) $PN 1
J 0
(-7390 780);
DISPLAY 0.617021 (-7390 780);
PAINT GREEN (-7390 780);
FORCEPROP 1 LAST VALUE 10UF
J 0
(-7350 750);
DISPLAY 0.617021 (-7350 750);
PAINT SKYBLUE (-7350 750);
FORCEPROP 1 LAST TOLERANCE 20%
J 0
(-7350 650);
DISPLAY 0.617021 (-7350 650);
PAINT SKYBLUE (-7350 650);
FORCEPROP 1 LAST MATERIAL X6S
J 0
(-7350 600);
DISPLAY 0.617021 (-7350 600);
PAINT SKYBLUE (-7350 600);
FORCEPROP 1 LASTPIN (-7400 600) $PN 2
J 0
(-7390 580);
DISPLAY 0.617021 (-7390 580);
PAINT GREEN (-7390 580);
FORCEPROP 0 LAST GROUP PWR_MLCC_CAP
J 0
(-7344 412);
DISPLAY 0.638298 (-7344 412);
PAINT BROWN (-7344 412);
DISPLAY BOTH (-7344 412);
FORCEPROP 2 LAST CDS_SEC 1
J 0
(-7350 900);
PAINT MONO (-7350 900);
DISPLAY INVISIBLE (-7350 900);
FORCEPROP 2 LAST $SEC 1
J 0
(-7350 900);
PAINT MONO (-7350 900);
DISPLAY INVISIBLE (-7350 900);
FORCEPROP 2 LAST ROOM PVPP_KLM_VR
J 0
(-7350 850);
PAINT MONO (-7350 850);
DISPLAY INVISIBLE (-7350 850);
FORCEPROP 2 LAST BOM_COST MEM_VRD_PVPP_AB
J 0
(-7350 850);
PAINT MONO (-7350 850);
DISPLAY INVISIBLE (-7350 850);
FORCEPROP 2 LAST CDS_LOCATION C3A4
J 0
(-7350 800);
DISPLAY 0.617021 (-7350 800);
PAINT AQUA (-7350 800);
DISPLAY INVISIBLE (-7350 800);
FORCEPROP 1 LAST PATH I93
J 0
(-7350 850);
DISPLAY 0.978723 (-7350 850);
PAINT WHITE (-7350 850);
DISPLAY INVISIBLE (-7350 850);
FORCEPROP 2 LAST CDS_LIB mstr_discrete
J 0
(-7400 700);
PAINT ORANGE (-7400 700);
DISPLAY INVISIBLE (-7400 700);
FORCEADD CAP..1
(-7675 725);
FORCEPROP 1 LAST VOLTAGE 4V
J 0
(-7625 725);
DISPLAY 0.638298 (-7625 725);
PAINT SKYBLUE (-7625 725);
FORCEPROP 1 LAST PART_NUMBER E15431-001
J 0
(-7625 575);
DISPLAY 0.617021 (-7625 575);
PAINT BLUE (-7625 575);
FORCEPROP 1 LAST TOLERANCE 20%
J 0
(-7625 675);
DISPLAY 0.617021 (-7625 675);
PAINT SKYBLUE (-7625 675);
FORCEPROP 1 LASTPIN (-7675 625) $PN 2
J 0
(-7665 605);
DISPLAY 0.617021 (-7665 605);
PAINT GREEN (-7665 605);
FORCEPROP 1 LAST MATERIAL X6S
J 0
(-7625 625);
DISPLAY 0.617021 (-7625 625);
PAINT SKYBLUE (-7625 625);
FORCEPROP 1 LAST PACK_TYPE 0603LF
J 0
(-7625 525);
DISPLAY 0.617021 (-7625 525);
PAINT SKYBLUE (-7625 525);
FORCEPROP 1 LASTPIN (-7675 825) $PN 1
J 0
(-7665 805);
DISPLAY 0.617021 (-7665 805);
PAINT GREEN (-7665 805);
FORCEPROP 1 LAST VALUE 10UF
J 0
(-7625 775);
DISPLAY 0.617021 (-7625 775);
PAINT SKYBLUE (-7625 775);
FORCEPROP 1 LAST LOCATION C3B1
J 0
(-7625 825);
DISPLAY 0.617021 (-7625 825);
PAINT AQUA (-7625 825);
FORCEPROP 0 LAST GROUP PWR_MLCC_CAP
J 0
(-7619 462);
DISPLAY 0.638298 (-7619 462);
PAINT BROWN (-7619 462);
DISPLAY BOTH (-7619 462);
FORCEPROP 2 LAST CDS_LIB mstr_discrete
J 0
(-7675 725);
PAINT ORANGE (-7675 725);
DISPLAY INVISIBLE (-7675 725);
FORCEPROP 2 LAST CDS_LOCATION C3B1
J 0
(-7625 825);
DISPLAY 0.617021 (-7625 825);
PAINT AQUA (-7625 825);
DISPLAY INVISIBLE (-7625 825);
FORCEPROP 2 LAST BOM_COST MEM_VRD_PVPP_AB
J 0
(-7625 875);
PAINT MONO (-7625 875);
DISPLAY INVISIBLE (-7625 875);
FORCEPROP 1 LAST PATH I94
J 0
(-7625 875);
DISPLAY 0.978723 (-7625 875);
PAINT WHITE (-7625 875);
DISPLAY INVISIBLE (-7625 875);
FORCEPROP 2 LAST ROOM PVPP_KLM_VR
J 0
(-7625 875);
PAINT MONO (-7625 875);
DISPLAY INVISIBLE (-7625 875);
FORCEPROP 2 LAST $SEC 1
J 0
(-7625 925);
PAINT MONO (-7625 925);
DISPLAY INVISIBLE (-7625 925);
FORCEPROP 2 LAST CDS_SEC 1
J 0
(-7625 925);
PAINT MONO (-7625 925);
DISPLAY INVISIBLE (-7625 925);
FORCEADD CAP..1
(-7950 725);
FORCEPROP 1 LAST VOLTAGE 4V
J 0
(-7900 725);
DISPLAY 0.638298 (-7900 725);
PAINT SKYBLUE (-7900 725);
FORCEPROP 1 LAST TOLERANCE 20%
J 0
(-7900 675);
DISPLAY 0.617021 (-7900 675);
PAINT SKYBLUE (-7900 675);
FORCEPROP 1 LAST MATERIAL X6S
J 0
(-7900 625);
DISPLAY 0.617021 (-7900 625);
PAINT SKYBLUE (-7900 625);
FORCEPROP 1 LAST VALUE 10UF
J 0
(-7900 775);
DISPLAY 0.617021 (-7900 775);
PAINT SKYBLUE (-7900 775);
FORCEPROP 1 LASTPIN (-7950 625) $PN 2
J 0
(-7940 605);
DISPLAY 0.617021 (-7940 605);
PAINT GREEN (-7940 605);
FORCEPROP 1 LAST PACK_TYPE 0603LF
J 0
(-7900 525);
DISPLAY 0.617021 (-7900 525);
PAINT SKYBLUE (-7900 525);
FORCEPROP 1 LASTPIN (-7950 825) $PN 1
J 0
(-7940 805);
DISPLAY 0.617021 (-7940 805);
PAINT GREEN (-7940 805);
FORCEPROP 1 LAST LOCATION C3A7
J 0
(-7900 825);
DISPLAY 0.617021 (-7900 825);
PAINT AQUA (-7900 825);
FORCEPROP 1 LAST PART_NUMBER E15431-001
J 0
(-7900 575);
DISPLAY 0.617021 (-7900 575);
PAINT BLUE (-7900 575);
FORCEPROP 0 LAST GROUP PWR_MLCC_CAP
J 0
(-7894 412);
DISPLAY 0.638298 (-7894 412);
PAINT BROWN (-7894 412);
DISPLAY BOTH (-7894 412);
FORCEPROP 2 LAST CDS_LIB mstr_discrete
J 0
(-7950 725);
PAINT ORANGE (-7950 725);
DISPLAY INVISIBLE (-7950 725);
FORCEPROP 2 LAST ROOM PVPP_KLM_VR
J 0
(-7900 875);
PAINT MONO (-7900 875);
DISPLAY INVISIBLE (-7900 875);
FORCEPROP 1 LAST PATH I95
J 0
(-7900 875);
DISPLAY 0.978723 (-7900 875);
PAINT WHITE (-7900 875);
DISPLAY INVISIBLE (-7900 875);
FORCEPROP 2 LAST CDS_LOCATION C3A7
J 0
(-7900 825);
DISPLAY 0.617021 (-7900 825);
PAINT AQUA (-7900 825);
DISPLAY INVISIBLE (-7900 825);
FORCEPROP 2 LAST $SEC 1
J 0
(-7900 925);
PAINT MONO (-7900 925);
DISPLAY INVISIBLE (-7900 925);
FORCEPROP 2 LAST CDS_SEC 1
J 0
(-7900 925);
PAINT MONO (-7900 925);
DISPLAY INVISIBLE (-7900 925);
FORCEPROP 2 LAST BOM_COST MEM_VRD_PVPP_AB
J 0
(-7900 875);
PAINT MONO (-7900 875);
DISPLAY INVISIBLE (-7900 875);
FORCEADD PVPP_KLM..1
(-8225 1000);
FORCEPROP 3 LASTPIN (-8225 950) SIG_NAME PVPP_KLM\g
J 0
(-8215 960);
DISPLAY 0.659574 (-8215 960);
PAINT MONO (-8215 960);
DISPLAY INVISIBLE (-8215 960);
FORCEPROP 1 LAST BODY_TYPE PLUMBING
J 0
(-8270 957);
DISPLAY 0.340426 (-8270 957);
PAINT GREEN (-8270 957);
DISPLAY INVISIBLE (-8270 957);
FORCEPROP 1 LAST VOLTAGE 2.5V
J 0
(-8270 957);
DISPLAY 0.340426 (-8270 957);
PAINT SKYBLUE (-8270 957);
DISPLAY INVISIBLE (-8270 957);
FORCEPROP 2 LAST CDS_LIB mstr_symbols
J 0
(-8225 1000);
PAINT ORANGE (-8225 1000);
DISPLAY INVISIBLE (-8225 1000);
FORCEPROP 1 LAST HDL_POWER PVPP_KLM
J 1
(-8225 1050);
DISPLAY 0.872340 (-8225 1050);
PAINT GREEN (-8225 1050);
DISPLAY INVISIBLE (-8225 1050);
FORCEPROP 2 LAST ROOM PVPP_KLM_VR
J 0
(-7975 1100);
PAINT ORANGE (-7975 1100);
DISPLAY INVISIBLE (-7975 1100);
FORCEPROP 1 LAST PATH I96
J 0
(-8175 1025);
DISPLAY 0.872340 (-8175 1025);
PAINT AQUA (-8175 1025);
DISPLAY INVISIBLE (-8175 1025);
FORCEPROP 2 LAST BOM_COST MEM_VRD_PVPP_AB
J 0
(-8150 1100);
PAINT MONO (-8150 1100);
DISPLAY INVISIBLE (-8150 1100);
FORCEADD CAP..1
(-8225 725);
FORCEPROP 1 LAST TOLERANCE 20%
J 0
(-8175 675);
DISPLAY 0.617021 (-8175 675);
PAINT SKYBLUE (-8175 675);
FORCEPROP 1 LAST VOLTAGE 4V
J 0
(-8175 725);
DISPLAY 0.638298 (-8175 725);
PAINT SKYBLUE (-8175 725);
FORCEPROP 1 LAST LOCATION C3A3
J 0
(-8175 825);
DISPLAY 0.617021 (-8175 825);
PAINT AQUA (-8175 825);
FORCEPROP 1 LASTPIN (-8225 825) $PN 1
J 0
(-8215 805);
DISPLAY 0.617021 (-8215 805);
PAINT GREEN (-8215 805);
FORCEPROP 1 LASTPIN (-8225 625) $PN 2
J 0
(-8215 605);
DISPLAY 0.617021 (-8215 605);
PAINT GREEN (-8215 605);
FORCEPROP 1 LAST MATERIAL X6S
J 0
(-8175 625);
DISPLAY 0.617021 (-8175 625);
PAINT SKYBLUE (-8175 625);
FORCEPROP 1 LAST PACK_TYPE 0603LF
J 0
(-8175 525);
DISPLAY 0.617021 (-8175 525);
PAINT SKYBLUE (-8175 525);
FORCEPROP 1 LAST VALUE 10UF
J 0
(-8175 775);
DISPLAY 0.617021 (-8175 775);
PAINT SKYBLUE (-8175 775);
FORCEPROP 1 LAST PART_NUMBER E15431-001
J 0
(-8175 575);
DISPLAY 0.617021 (-8175 575);
PAINT BLUE (-8175 575);
FORCEPROP 0 LAST GROUP PWR_MLCC_CAP
J 0
(-8169 462);
DISPLAY 0.638298 (-8169 462);
PAINT BROWN (-8169 462);
DISPLAY BOTH (-8169 462);
FORCEPROP 2 LAST CDS_LIB mstr_discrete
J 0
(-8225 725);
PAINT ORANGE (-8225 725);
DISPLAY INVISIBLE (-8225 725);
FORCEPROP 2 LAST CDS_LOCATION C3A3
J 0
(-8175 825);
DISPLAY 0.617021 (-8175 825);
PAINT AQUA (-8175 825);
DISPLAY INVISIBLE (-8175 825);
FORCEPROP 2 LAST BOM_COST MEM_VRD_PVPP_AB
J 0
(-8175 875);
PAINT MONO (-8175 875);
DISPLAY INVISIBLE (-8175 875);
FORCEPROP 1 LAST PATH I97
J 0
(-8175 875);
DISPLAY 0.978723 (-8175 875);
PAINT WHITE (-8175 875);
DISPLAY INVISIBLE (-8175 875);
FORCEPROP 2 LAST ROOM PVPP_KLM_VR
J 0
(-8175 875);
PAINT MONO (-8175 875);
DISPLAY INVISIBLE (-8175 875);
FORCEPROP 2 LAST CDS_SEC 1
J 0
(-8175 925);
PAINT MONO (-8175 925);
DISPLAY INVISIBLE (-8175 925);
FORCEPROP 2 LAST $SEC 1
J 0
(-8175 925);
PAINT MONO (-8175 925);
DISPLAY INVISIBLE (-8175 925);
FORCEADD INTEL_CORP_BPAGE..1
(-375 -75);
FORCEPROP 1 LAST CDS_CON_LAST_MODIFIED Fri Jun 16 17:49:23 2017
J 0
(-1800 250);
DISPLAY 0.489362 (-1800 250);
PAINT GREEN (-1800 250);
DISPLAY INVISIBLE (-1800 250);
FORCEPROP 1 LAST CUSTOM_TXT_CDS <CURRENT_DESIGN_SHEET> OF <TOTAL_DESIGN_SHEETS>
J 0
(-875 -50);
PAINT ORANGE (-875 -50);
FORCEPROP 1 LAST CUSTOM_TXT_CDS <CON_LAST_MODIFIED>
J 0
(-4375 25);
PAINT ORANGE (-4375 25);
FORCEPROP 2 LAST CUSTOM_TXT_CDS <XR_PAGE_TITLE>
J 0
(-8265 5175);
DISPLAY 0.638298 (-8265 5175);
PAINT PINK (-8265 5175);
DISPLAY INVISIBLE (-8265 5175);
FORCEPROP 1 LAST SCH_TITLE VPP KLM VR
J 0
(-8275 50);
DISPLAY 1.212766 (-8275 50);
PAINT GREEN (-8275 50);
FORCEPROP 2 LAST PAGE_BORDER TRUE
J 0
(-8265 5175);
DISPLAY 0.425532 (-8265 5175);
PAINT PINK (-8265 5175);
DISPLAY INVISIBLE (-8265 5175);
FORCEPROP 1 LAST COMMENT_BODY TRUE
J 0
(-363 -63);
DISPLAY 0.212766 (-363 -63);
PAINT GREEN (-363 -63);
DISPLAY INVISIBLE (-363 -63);
FORCEPROP 2 LAST CDS_LIB mstr_symbols
J 0
(-375 -75);
DISPLAY 0.489362 (-375 -75);
PAINT ORANGE (-375 -75);
DISPLAY INVISIBLE (-375 -75);
FORCEPROP 2 LAST CDS_XR_PAGE_TITLE CR-234 : @BASEBOARD_FAB2_LIB.BASEBOARD_FAB2(SCH_1):PAGE234
J 0
(-8265 5175);
DISPLAY 0.638298 (-8265 5175);
PAINT PINK (-8265 5175);
DISPLAY INVISIBLE (-8265 5175);
FORCEADD DNS..2
(-2570 3595);
PAINT RED (-2570 3595);
FORCEPROP 2 LAST CDS_LIB mstr_misc
J 0
(-2570 3595);
PAINT ORANGE (-2570 3595);
DISPLAY INVISIBLE (-2570 3595);
FORCEPROP 1 LAST COMMENT_BODY TRUE
R 1
J 0
(-2495 3370);
DISPLAY 0.872340 (-2495 3370);
PAINT GREEN (-2495 3370);
DISPLAY INVISIBLE (-2495 3370);
FORCEADD DNS..2
(-6295 2395);
PAINT RED (-6295 2395);
FORCEPROP 2 LAST CDS_LIB mstr_misc
J 0
(-6295 2395);
PAINT ORANGE (-6295 2395);
DISPLAY INVISIBLE (-6295 2395);
FORCEPROP 1 LAST COMMENT_BODY TRUE
R 1
J 0
(-6220 2170);
DISPLAY 0.872340 (-6220 2170);
PAINT GREEN (-6220 2170);
DISPLAY INVISIBLE (-6220 2170);
FORCEADD DNS..2
(-2570 3270);
PAINT RED (-2570 3270);
FORCEPROP 1 LAST COMMENT_BODY TRUE
R 1
J 0
(-2495 3045);
DISPLAY 0.872340 (-2495 3045);
PAINT GREEN (-2495 3045);
DISPLAY INVISIBLE (-2495 3045);
FORCEPROP 2 LAST CDS_LIB mstr_misc
J 0
(-2570 3270);
PAINT ORANGE (-2570 3270);
DISPLAY INVISIBLE (-2570 3270);
WIRE 16 -1 (-3875 625)(-3875 525);
WIRE 16 -1 (-4225 1475)(-4225 1350);
WIRE 16 -1 (-5100 3950)(-5100 4050);
WIRE 16 -1 (-7850 4450)(-7850 4300);
WIRE 16 -1 (-7850 4300)(-7750 4300);
WIRE 16 -1 (-3075 2025)(-3075 1975);
WIRE 16 -1 (-3075 2075)(-3075 2025);
WIRE 16 -1 (-3300 2025)(-3075 2025);
WIRE 16 -1 (-3075 2125)(-3075 2075);
WIRE 16 -1 (-3300 2075)(-3075 2075);
WIRE 16 -1 (-3075 2175)(-3075 2125);
WIRE 16 -1 (-3300 2125)(-3075 2125);
WIRE 16 -1 (-3075 2225)(-3075 2175);
WIRE 16 -1 (-3300 2175)(-3075 2175);
WIRE 16 -1 (-3075 2275)(-3075 2225);
WIRE 16 -1 (-3300 2225)(-3075 2225);
WIRE 16 -1 (-3075 2325)(-3075 2275);
WIRE 16 -1 (-3300 2275)(-3075 2275);
WIRE 16 -1 (-3075 2375)(-3075 2325);
WIRE 16 -1 (-3300 2325)(-3075 2325);
WIRE 16 -1 (-3075 2425)(-3075 2375);
WIRE 16 -1 (-3300 2375)(-3075 2375);
WIRE 16 -1 (-3075 2475)(-3075 2425);
WIRE 16 -1 (-3300 2425)(-3075 2425);
WIRE 16 -1 (-3075 2525)(-3075 2475);
WIRE 16 -1 (-3300 2475)(-3075 2475);
WIRE 16 -1 (-3075 2575)(-3075 2525);
WIRE 16 -1 (-3300 2525)(-3075 2525);
WIRE 16 -1 (-3075 2625)(-3075 2575);
WIRE 16 -1 (-3300 2575)(-3075 2575);
WIRE 16 -1 (-3075 2675)(-3075 2625);
WIRE 16 -1 (-3300 2625)(-3075 2625);
WIRE 16 -1 (-3075 2725)(-3075 2675);
WIRE 16 -1 (-3300 2675)(-3075 2675);
WIRE 16 -1 (-3300 2725)(-3075 2725);
WIRE 16 -1 (-2575 3175)(-2575 3150);
WIRE 16 -1 (-2050 3450)(-2050 3550);
WIRE 16 -1 (-1750 3400)(-1750 3550);
WIRE 16 -1 (-1450 3400)(-1450 3550);
WIRE 16 -1 (-1150 3400)(-1150 3600);
WIRE 16 -1 (-850 3400)(-850 3600);
WIRE 16 -1 (-800 3925)(-800 3850);
WIRE 16 -1 (-575 3850)(-800 3850);
WIRE 16 -1 (-800 3850)(-850 3850);
WIRE 16 -1 (-1150 3850)(-850 3850);
WIRE 16 -1 (-850 3850)(-850 3800);
WIRE 16 -1 (-575 3850)(-575 3250);
WIRE 16 -1 (-1350 3250)(-575 3250);
WIRE 16 -1 (-1150 3850)(-1450 3850);
WIRE 16 -1 (-1150 3850)(-1150 3800);
WIRE 16 -1 (-1750 3850)(-1450 3850);
WIRE 16 -1 (-1450 3750)(-1450 3850);
WIRE 16 -1 (-1350 3250)(-1350 3150);
WIRE 16 -1 (-2050 3850)(-1750 3850);
WIRE 16 -1 (-1750 3850)(-1750 3750);
WIRE 16 -1 (-2050 3750)(-2050 3850);
WIRE 16 -1 (-2200 3850)(-2050 3850);
WIRE 16 -1 (-6300 2125)(-6300 2300);
WIRE 16 -1 (-5650 2200)(-5650 2300);
WIRE 16 -1 (-5075 2075)(-5075 2000);
WIRE 16 -1 (-4750 1550)(-4750 1400);
WIRE 16 -1 (-4375 1900)(-4375 2025);
WIRE 16 -1 (-4375 2025)(-4300 2025);
WIRE 16 -1 (-5175 3425)(-5175 3350);
WIRE 16 -1 (-5400 2750)(-5400 2925);
WIRE 16 -1 (-5400 2925)(-4300 2925);
WIRE 16 -1 (-6750 3950)(-6750 4050);
WIRE 16 -1 (-6375 3950)(-6375 4050);
WIRE 16 -1 (-5925 3950)(-5925 4050);
WIRE 16 -1 (-5475 3950)(-5475 4050);
WIRE 16 -1 (-1350 1100)(-1350 1350);
WIRE 16 -1 (-7350 4025)(-7350 3900);
WIRE 16 -1 (-7050 4025)(-7050 3900);
WIRE 16 -1 (-1450 600)(-1450 650);
WIRE 16 -1 (-1450 650)(-1250 650);
WIRE 16 -1 (-900 600)(-900 650);
WIRE 16 -1 (-900 650)(-1050 650);
WIRE 16 -1 (-8225 350)(-8225 325);
WIRE 16 -1 (-8225 350)(-7950 350);
WIRE 16 -1 (-8225 625)(-8225 350);
WIRE 16 -1 (-7950 350)(-7675 350);
WIRE 16 -1 (-7950 625)(-7950 350);
WIRE 16 -1 (-7675 350)(-7400 350);
WIRE 16 -1 (-7675 625)(-7675 350);
WIRE 16 -1 (-7400 350)(-7125 350);
WIRE 16 -1 (-7400 600)(-7400 350);
WIRE 16 -1 (-6825 350)(-7125 350);
WIRE 16 -1 (-7125 625)(-7125 350);
WIRE 16 -1 (-6825 350)(-6550 350);
WIRE 16 -1 (-6825 625)(-6825 350);
WIRE 16 -1 (-6550 350)(-6250 350);
WIRE 16 -1 (-6550 625)(-6550 350);
WIRE 16 -1 (-6250 350)(-5950 350);
WIRE 16 -1 (-6250 625)(-6250 350);
WIRE 16 -1 (-5950 350)(-5675 350);
WIRE 16 -1 (-5950 625)(-5950 350);
WIRE 16 -1 (-5675 350)(-5400 350);
WIRE 16 -1 (-5675 600)(-5675 350);
WIRE 16 -1 (-5125 350)(-5400 350);
WIRE 16 -1 (-5400 600)(-5400 350);
WIRE 16 -1 (-5125 625)(-5125 350);
WIRE 16 -1 (-8225 900)(-8225 950);
WIRE 16 -1 (-7950 900)(-8225 900);
WIRE 16 -1 (-8225 900)(-8225 825);
WIRE 16 -1 (-7675 900)(-7950 900);
WIRE 16 -1 (-7950 825)(-7950 900);
WIRE 16 -1 (-7400 900)(-7675 900);
WIRE 16 -1 (-7675 825)(-7675 900);
WIRE 16 -1 (-7125 900)(-7400 900);
WIRE 16 -1 (-7400 800)(-7400 900);
WIRE 16 -1 (-6825 900)(-7125 900);
WIRE 16 -1 (-7125 825)(-7125 900);
WIRE 16 -1 (-6550 900)(-6825 900);
WIRE 16 -1 (-6825 825)(-6825 900);
WIRE 16 -1 (-6250 900)(-6550 900);
WIRE 16 -1 (-6550 900)(-6550 825);
WIRE 16 -1 (-5950 900)(-6250 900);
WIRE 16 -1 (-6250 825)(-6250 900);
WIRE 16 -1 (-5675 900)(-5950 900);
WIRE 16 -1 (-5950 825)(-5950 900);
WIRE 16 -1 (-5400 900)(-5675 900);
WIRE 16 -1 (-5675 800)(-5675 900);
WIRE 16 -1 (-5125 900)(-5400 900);
WIRE 16 -1 (-5400 800)(-5400 900);
WIRE 16 -1 (-5125 825)(-5125 900);
WIRE 16 -1 (-7550 4300)(-7350 4300);
WIRE 16 -1 (-7350 4175)(-7350 4300);
WIRE 16 -1 (-4300 3125)(-4725 3125);
WIRE 16 -1 (-7050 4300)(-7350 4300);
WIRE 16 -1 (-7050 4300)(-7050 4175);
WIRE 16 -1 (-7050 4300)(-6750 4300);
WIRE 16 -1 (-6750 4250)(-6750 4300);
WIRE 16 -1 (-4725 3125)(-4725 3175);
WIRE 16 -1 (-4300 3175)(-4725 3175);
WIRE 16 -1 (-4725 3175)(-4725 3225);
WIRE 16 -1 (-4300 3225)(-4725 3225);
WIRE 16 -1 (-6375 4300)(-6750 4300);
WIRE 16 -1 (-6375 4250)(-6375 4300);
WIRE 16 -1 (-5925 4300)(-6375 4300);
WIRE 16 -1 (-5925 4250)(-5925 4300);
WIRE 16 -1 (-4725 3225)(-4725 3275);
WIRE 16 -1 (-4300 3275)(-4725 3275);
WIRE 16 -1 (-4725 3275)(-4725 3325);
WIRE 16 -1 (-4300 3325)(-4725 3325);
WIRE 16 -1 (-5475 4300)(-5925 4300);
FORCEPROP 0 LAST SIG_NAME VR_FET_SW_P12V_STBY_PVPP_KLM
J 0
(-5910 4310);
DISPLAY 0.617021 (-5910 4310);
PAINT ORANGE (-5910 4310);
FORCEPROP 2 LASTPROP $XRERR UNIQUE?
J 0
(-6150 4310);
DISPLAY 0.638298 (-6150 4310);
PAINT MONO (-6150 4310);
DISPLAY INVISIBLE (-6150 4310);
WIRE 16 -1 (-5475 4250)(-5475 4300);
WIRE 16 -1 (-5100 4300)(-5475 4300);
WIRE 16 -1 (-5100 4250)(-5100 4300);
WIRE 16 -1 (-4725 3325)(-4725 3375);
WIRE 16 -1 (-4300 3375)(-4725 3375);
WIRE 16 -1 (-4725 3375)(-4725 3425);
WIRE 16 -1 (-4300 3425)(-4725 3425);
WIRE 16 -1 (-4725 4300)(-5100 4300);
WIRE 16 -1 (-5175 3625)(-5175 3750);
WIRE 16 -1 (-5175 3750)(-4725 3750);
WIRE 16 -1 (-4725 4300)(-4725 3750);
WIRE 16 -1 (-4725 3425)(-4725 3475);
WIRE 16 -1 (-4725 3475)(-4300 3475);
WIRE 16 -1 (-4725 3575)(-4725 3475);
WIRE 16 -1 (-4725 3750)(-4725 3575);
WIRE 16 -1 (-4300 3575)(-4725 3575);
WIRE 16 -1 (-4300 2825)(-5825 2825);
FORCEPROP 2 LAST SIG_NAME FM_PVPP_PVDDQ_CPU1_EN_KLM
J 0
(-5276 2850);
DISPLAY 0.617021 (-5276 2850);
PAINT ORANGE (-5276 2850);
FORCEPROP 2 LASTPROP $XRERR UNIQUE?
J 0
(-5516 2850);
DISPLAY 0.638298 (-5516 2850);
PAINT MONO (-5516 2850);
DISPLAY INVISIBLE (-5516 2850);
WIRE 16 -1 (-5075 2725)(-5075 2275);
FORCEPROP 2 LAST SIG_NAME VR_PVPP_KLM_SS
R 1
J 0
(-5085 2285);
DISPLAY 0.617021 (-5085 2285);
PAINT ORANGE (-5085 2285);
FORCEPROP 2 LASTPROP $XRERR UNIQUE?
J 0
(-5325 2285);
DISPLAY 0.638298 (-5325 2285);
PAINT MONO (-5325 2285);
DISPLAY INVISIBLE (-5325 2285);
WIRE 16 -1 (-4300 2725)(-5075 2725);
WIRE 68 -1 (-7400 3825)(-6800 3825);
WIRE 68 -1 (-6800 3825)(-6800 4375);
WIRE 68 -1 (-7400 4375)(-7400 3825);
WIRE 68 -1 (-7400 4375)(-6800 4375);
WIRE 3 682 (-4350 4300)(-4350 4025);
WIRE 3 682 (-4025 4300)(-4350 4300);
WIRE 3 682 (-4350 4025)(-4025 4025);
WIRE 3 682 (-4025 4025)(-4025 4300);
WIRE 16 682 (-650 4600)(-2000 4600);
WIRE 16 682 (-650 4100)(-650 4600);
WIRE 16 682 (-2000 4600)(-2000 4100);
WIRE 16 682 (-2000 4100)(-650 4100);
WIRE 16 2175 (-8300 1150)(-8300 250);
WIRE 16 2175 (-4825 250)(-8300 250);
WIRE 16 2175 (-8300 1150)(-4825 1150);
WIRE 16 2175 (-4825 1150)(-4825 250);
WIRE 16 2175 (-1400 1150)(-700 1150);
WIRE 16 2175 (-700 3200)(-700 1150);
WIRE 16 2175 (-1400 1150)(-1400 3200);
WIRE 16 2175 (-1400 3200)(-700 3200);
WIRE 16 -1 (-2575 3375)(-2575 3500);
FORCEPROP 2 LAST SIG_NAME VR_PVPP_KLM_SNUB
J 0
(-2560 3435);
DISPLAY 0.617021 (-2560 3435);
PAINT ORANGE (-2560 3435);
FORCEPROP 2 LASTPROP $XRERR UNIQUE?
J 0
(-2800 3435);
DISPLAY 0.638298 (-2800 3435);
PAINT MONO (-2800 3435);
DISPLAY INVISIBLE (-2800 3435);
WIRE 16 -1 (-2525 975)(-3250 975);
FORCEPROP 2 LAST SIG_NAME PWRGD_PVPP_KLM
J 0
(-2960 985);
DISPLAY 0.617021 (-2960 985);
PAINT ORANGE (-2960 985);
WIRE 16 -1 (-6300 2825)(-7600 2825);
FORCEPROP 2 LAST SIG_NAME FM_PVPP_CPU1_EN
J 0
(-7601 2850);
DISPLAY 0.617021 (-7601 2850);
PAINT ORANGE (-7601 2850);
WIRE 16 -1 (-6300 2500)(-6300 2825);
WIRE 16 -1 (-6025 2825)(-6300 2825);
WIRE 16 -1 (-3275 4200)(-3025 4200);
WIRE 16 -1 (-2575 3700)(-2575 3850);
WIRE 16 -1 (-2400 3850)(-2575 3850);
WIRE 16 -1 (-3025 3850)(-2575 3850);
FORCEPROP 2 LAST SIG_NAME VR_PVPP_KLM_PHASE
J 0
(-3010 3860);
DISPLAY 0.617021 (-3010 3860);
PAINT ORANGE (-3010 3860);
FORCEPROP 2 LASTPROP $XRERR UNIQUE?
J 0
(-3250 3860);
DISPLAY 0.638298 (-3250 3860);
PAINT MONO (-3250 3860);
DISPLAY INVISIBLE (-3250 3860);
WIRE 16 -1 (-3025 4200)(-3025 3850);
WIRE 16 -1 (-3300 3475)(-3025 3475);
WIRE 16 -1 (-3025 3475)(-3025 3850);
WIRE 16 -1 (-3300 3425)(-3025 3425);
WIRE 16 -1 (-3025 3425)(-3025 3475);
WIRE 16 -1 (-3300 3375)(-3025 3375);
WIRE 16 -1 (-3025 3375)(-3025 3425);
WIRE 16 -1 (-3300 3325)(-3025 3325);
WIRE 16 -1 (-3025 3325)(-3025 3375);
WIRE 16 -1 (-3300 3275)(-3025 3275);
WIRE 16 -1 (-3025 3275)(-3025 3325);
WIRE 16 -1 (-3300 3225)(-3025 3225);
WIRE 16 -1 (-3025 3225)(-3025 3275);
WIRE 16 -1 (-3300 3175)(-3025 3175);
WIRE 16 -1 (-3025 3175)(-3025 3225);
WIRE 16 -1 (-3300 3125)(-3025 3125);
WIRE 16 -1 (-3025 3125)(-3025 3175);
WIRE 16 -1 (-3025 3025)(-3025 3125);
WIRE 16 -1 (-3300 3025)(-3025 3025);
WIRE 16 -1 (-3475 4200)(-4050 4200);
FORCEPROP 2 LAST SIG_NAME VR_PVPP_KLM_BOOT_R
J 0
(-4030 4210);
DISPLAY 0.617021 (-4030 4210);
PAINT ORANGE (-4030 4210);
FORCEPROP 2 LASTPROP $XRERR UNIQUE?
J 0
(-4270 4210);
DISPLAY 0.638298 (-4270 4210);
PAINT MONO (-4270 4210);
DISPLAY INVISIBLE (-4270 4210);
WIRE 16 -1 (-2950 2450)(-3000 2450);
WIRE 16 -1 (-3000 2450)(-3000 2825);
FORCEPROP 0 LAST SIG_NAME VR_COMP_PVPP_KLM_3
J 0
(-2910 2835);
DISPLAY 0.617021 (-2910 2835);
PAINT ORANGE (-2910 2835);
FORCEPROP 2 LASTPROP $XRERR UNIQUE?
J 0
(-3150 2835);
DISPLAY 0.638298 (-3150 2835);
PAINT MONO (-3150 2835);
DISPLAY INVISIBLE (-3150 2835);
WIRE 16 -1 (-3000 2825)(-2325 2825);
WIRE 16 -1 (-3300 2825)(-3000 2825);
WIRE 16 -1 (-1350 2275)(-1350 2900);
FORCEPROP 0 LAST SIG_NAME VSENSE_PVPP_KLM
R 1
J 0
(-1360 2310);
DISPLAY 0.617021 (-1360 2310);
PAINT ORANGE (-1360 2310);
FORCEPROP 2 LASTPROP $XRERR UNIQUE?
J 0
(-1600 2310);
DISPLAY 0.638298 (-1600 2310);
PAINT MONO (-1600 2310);
DISPLAY INVISIBLE (-1600 2310);
WIRE 16 -1 (-1350 2900)(-1350 2950);
WIRE 16 -1 (-1025 2900)(-1350 2900);
WIRE 16 -1 (-1025 2850)(-1025 2900);
WIRE 16 -1 (-1025 2050)(-1025 2650);
FORCEPROP 0 LAST SIG_NAME VR_COMP_PVPP_KLM
R 1
J 0
(-1035 2135);
DISPLAY 0.617021 (-1035 2135);
PAINT ORANGE (-1035 2135);
FORCEPROP 2 LASTPROP $XRERR UNIQUE?
J 0
(-1275 2135);
DISPLAY 0.638298 (-1275 2135);
PAINT MONO (-1275 2135);
DISPLAY INVISIBLE (-1275 2135);
WIRE 16 -1 (-2250 2450)(-2750 2450);
FORCEPROP 0 LAST SIG_NAME VR_COMP_RC_PVPP_KLM
J 0
(-2735 2460);
DISPLAY 0.617021 (-2735 2460);
PAINT ORANGE (-2735 2460);
FORCEPROP 2 LASTPROP $XRERR UNIQUE?
J 0
(-2975 2460);
DISPLAY 0.638298 (-2975 2460);
PAINT MONO (-2975 2460);
DISPLAY INVISIBLE (-2975 2460);
WIRE 16 2175 (-4400 4000)(-4400 4375);
WIRE 16 2175 (-3175 4000)(-4400 4000);
WIRE 16 2175 (-4400 4375)(-3175 4375);
WIRE 16 2175 (-3175 4375)(-3175 4000);
WIRE 16 -1 (-4250 4200)(-4300 4200);
WIRE 16 -1 (-4300 4200)(-4300 3900);
FORCEPROP 2 LAST SIG_NAME VR_PVPP_KLM_BOOT
J 0
(-4210 3935);
DISPLAY 0.617021 (-4210 3935);
PAINT ORANGE (-4210 3935);
FORCEPROP 2 LASTPROP $XRERR UNIQUE?
J 0
(-4450 3935);
DISPLAY 0.638298 (-4450 3935);
PAINT MONO (-4450 3935);
DISPLAY INVISIBLE (-4450 3935);
WIRE 16 -1 (-3250 3575)(-3300 3575);
WIRE 16 -1 (-4300 3900)(-3250 3900);
WIRE 16 -1 (-3250 3900)(-3250 3575);
WIRE 16 -1 (-5650 3025)(-4300 3025);
FORCEPROP 0 LAST SIG_NAME VR_VB_PVPP_KLM
J 0
(-5360 3035);
DISPLAY 0.617021 (-5360 3035);
PAINT ORANGE (-5360 3035);
FORCEPROP 2 LASTPROP $XRERR UNIQUE?
J 0
(-5600 3035);
DISPLAY 0.638298 (-5600 3035);
PAINT MONO (-5600 3035);
DISPLAY INVISIBLE (-5600 3035);
WIRE 16 -1 (-5650 2500)(-5650 3025);
WIRE 3 682 (-5850 2550)(-5850 2150);
WIRE 3 682 (-5250 2550)(-5850 2550);
WIRE 3 682 (-5850 2150)(-5250 2150);
WIRE 3 682 (-5250 2150)(-5250 2550);
WIRE 16 -1 (-1975 2450)(-2050 2450);
WIRE 16 -1 (-2125 2825)(-1975 2825);
WIRE 16 -1 (-1975 2450)(-1975 2825);
WIRE 16 -1 (-3300 2925)(-1975 2925);
WIRE 16 -1 (-1975 2825)(-1975 2925);
WIRE 16 -1 (-1875 2925)(-1975 2925);
WIRE 16 -1 (-1875 1725)(-1875 2925);
WIRE 16 -1 (-1875 1725)(-1350 1725);
FORCEPROP 0 LAST SIG_NAME VR_FB_PVPP_KLM
J 0
(-1835 1735);
DISPLAY 0.617021 (-1835 1735);
PAINT ORANGE (-1835 1735);
FORCEPROP 2 LASTPROP $XRERR UNIQUE?
J 0
(-2075 1735);
DISPLAY 0.638298 (-2075 1735);
PAINT MONO (-2075 1735);
DISPLAY INVISIBLE (-2075 1735);
WIRE 16 -1 (-1350 1725)(-1350 1550);
WIRE 16 -1 (-1350 1800)(-1350 1725);
WIRE 16 -1 (-1350 2075)(-1350 1800);
WIRE 16 -1 (-1025 1800)(-1350 1800);
WIRE 16 -1 (-1025 1850)(-1025 1800);
WIRE 3 682 (-1450 1200)(-1050 1200);
WIRE 3 682 (-1450 1650)(-1450 1200);
WIRE 3 682 (-1050 1200)(-1050 1650);
WIRE 3 682 (-1050 1650)(-1450 1650);
WIRE 16 2175 (-5200 3800)(-7450 3800);
WIRE 16 2175 (-5200 4350)(-5200 3800);
WIRE 16 2175 (-7450 3800)(-7450 4350);
WIRE 16 2175 (-7450 4350)(-5200 4350);
WIRE 16 -1 (-4750 2625)(-4300 2625);
WIRE 16 -1 (-4750 1750)(-4750 2625);
FORCEPROP 2 LAST SIG_NAME VR_PVPP_KLM_ISET
R 1
J 0
(-4760 2110);
DISPLAY 0.617021 (-4760 2110);
PAINT ORANGE (-4760 2110);
FORCEPROP 2 LASTPROP $XRERR UNIQUE?
J 0
(-5000 2110);
DISPLAY 0.638298 (-5000 2110);
PAINT MONO (-5000 2110);
DISPLAY INVISIBLE (-5000 2110);
WIRE 16 -1 (-3875 825)(-3875 975);
WIRE 16 -1 (-3450 975)(-3875 975);
FORCEPROP 2 LAST SIG_NAME PWRGD_PVPP_KLM_R
J 0
(-3985 985);
DISPLAY 0.617021 (-3985 985);
PAINT ORANGE (-3985 985);
FORCEPROP 2 LASTPROP $XRERR UNIQUE?
J 0
(-4225 985);
DISPLAY 0.638298 (-4225 985);
PAINT MONO (-4225 985);
DISPLAY INVISIBLE (-4225 985);
WIRE 16 -1 (-4225 1150)(-4225 975);
WIRE 16 -1 (-3875 975)(-4225 975);
WIRE 16 -1 (-4225 975)(-4550 975);
WIRE 16 -1 (-4550 975)(-4550 2525);
WIRE 16 -1 (-4300 2525)(-4550 2525);
WIRE 3 682 (-5250 1300)(-5250 1850);
WIRE 3 682 (-4600 1300)(-5250 1300);
WIRE 3 682 (-5250 1850)(-4600 1850);
WIRE 3 682 (-4600 1850)(-4600 1300);
DOT 1 (-1450 3850);
DOT 1 (-7350 4300);
DOT 1 (-6750 4300);
DOT 1 (-3075 2175);
DOT 1 (-7050 4300);
DOT 1 (-5100 4300);
DOT 1 (-2575 3850);
DOT 1 (-1350 1800);
DOT 1 (-1350 2900);
DOT 1 (-2050 3850);
DOT 1 (-800 3850);
DOT 1 (-850 3850);
DOT 1 (-1150 3850);
DOT 1 (-1750 3850);
DOT 1 (-1975 2925);
DOT 1 (-1975 2825);
DOT 1 (-3025 3850);
DOT 1 (-3025 3475);
DOT 1 (-3025 3375);
DOT 1 (-3025 3425);
DOT 1 (-3025 3325);
DOT 1 (-3025 3275);
DOT 1 (-3025 3225);
DOT 1 (-3025 3125);
DOT 1 (-3025 3175);
DOT 1 (-3000 2825);
DOT 1 (-3075 2575);
DOT 1 (-3075 2625);
DOT 1 (-3075 2675);
DOT 1 (-3075 2475);
DOT 1 (-3075 2525);
DOT 1 (-3075 2325);
DOT 1 (-3075 2425);
DOT 1 (-3075 2375);
DOT 1 (-3075 2275);
DOT 1 (-3075 2225);
DOT 1 (-3075 2075);
DOT 1 (-3075 2125);
DOT 1 (-3075 2025);
DOT 1 (-3875 975);
DOT 1 (-5475 4300);
DOT 1 (-5925 4300);
DOT 1 (-6375 4300);
DOT 1 (-4725 3750);
DOT 1 (-4725 3575);
DOT 1 (-4725 3475);
DOT 1 (-4725 3425);
DOT 1 (-4725 3375);
DOT 1 (-4725 3325);
DOT 1 (-4725 3275);
DOT 1 (-4725 3225);
DOT 1 (-4725 3175);
DOT 1 (-4225 975);
DOT 1 (-5400 900);
DOT 1 (-5950 900);
DOT 1 (-6300 2825);
DOT 1 (-6250 900);
DOT 1 (-6550 900);
DOT 1 (-6825 900);
DOT 1 (-7125 900);
DOT 1 (-7400 900);
DOT 1 (-8225 900);
DOT 1 (-7950 900);
DOT 1 (-7675 900);
DOT 1 (-1350 1725);
DOT 1 (-8225 350);
DOT 1 (-7950 350);
DOT 1 (-7400 350);
DOT 1 (-7125 350);
DOT 1 (-6825 350);
DOT 1 (-6550 350);
DOT 1 (-6250 350);
DOT 1 (-5950 350);
DOT 1 (-5675 350);
DOT 1 (-5400 350);
DOT 1 (-7675 350);
DOT 1 (-5675 900);
FORCENOTE
IOUT DI/DT = 21.5A/US
(-1975 4175) 0;
DISPLAY LEFT (-1975 4175);
DISPLAY 1.021277 (-1975 4175);
PAINT PURPLE (-1975 4175);
FORCENOTE
SPOF
(-930 3050) 0;
DISPLAY LEFT (-930 3050);
DISPLAY 2.340426 (-930 3050);
PAINT PURPLE (-930 3050);
FORCENOTE
TP FAB1 CHANGE ONE 47UF CPA TO TWO 22UF CAPS 0107
(-7675 3750) 0;
DISPLAY LEFT (-7675 3750);
DISPLAY 1.021277 (-7675 3750);
PAINT RED (-7675 3750);
FORCENOTE
BOM_COST: PVPP_KLM_VR
(-7475 25) 0;
DISPLAY LEFT (-7475 25);
DISPLAY 0.787234 (-7475 25);
PAINT PURPLE (-7475 25);
FORCENOTE
ROOM = PVPP_KLM_VR
(-7475 75) 0;
DISPLAY LEFT (-7475 75);
DISPLAY 0.787234 (-7475 75);
PAINT PURPLE (-7475 75);
FORCENOTE
POINT ONLY TOP TO L2
(-1500 800) 0;
DISPLAY LEFT (-1500 800);
DISPLAY 1.042553 (-1500 800);
PAINT PURPLE (-1500 800);
FORCENOTE
SPOF
(-4400 4425) 0;
DISPLAY LEFT (-4400 4425);
DISPLAY 1.659574 (-4400 4425);
PAINT PURPLE (-4400 4425);
FORCENOTE
TOP LAYER
(-3725 4425) 0;
DISPLAY LEFT (-3725 4425);
DISPLAY 1.042553 (-3725 4425);
PAINT PURPLE (-3725 4425);
FORCENOTE
TP FAB1 CHANGE RES PACKAGE TO 0603
(-4375 4325) 0;
DISPLAY LEFT (-4375 4325);
DISPLAY 0.638298 (-4375 4325);
PAINT RED (-4375 4325);
FORCENOTE
VOUT = 2.5V
(-1975 4525) 0;
DISPLAY LEFT (-1975 4525);
DISPLAY 1.021277 (-1975 4525);
PAINT PURPLE (-1975 4525);
FORCENOTE
IOUT STEP = 5.3A
(-1975 4225) 0;
DISPLAY LEFT (-1975 4225);
DISPLAY 1.021277 (-1975 4225);
PAINT PURPLE (-1975 4225);
FORCENOTE
DC TOL = +/-1.5%
(-1975 4425) 0;
DISPLAY LEFT (-1975 4425);
DISPLAY 1.021277 (-1975 4425);
PAINT PURPLE (-1975 4425);
FORCENOTE
IOUT PK = 10.1A (INCLUDED CPU PVPP)
(-1975 4275) 0;
DISPLAY LEFT (-1975 4275);
DISPLAY 1.021277 (-1975 4275);
PAINT PURPLE (-1975 4275);
FORCENOTE
IOUT TDC = 7.21A (INCLUDED CPU PVPP)
(-1975 4325) 0;
DISPLAY LEFT (-1975 4325);
DISPLAY 1.021277 (-1975 4325);
PAINT PURPLE (-1975 4325);
FORCENOTE
AC & RIPPLE TOL = +3.5%, -7.3%
(-1975 4375) 0;
DISPLAY LEFT (-1975 4375);
DISPLAY 1.021277 (-1975 4375);
PAINT PURPLE (-1975 4375);
FORCENOTE
CONNECT AT SINGLE
(-1450 850) 0;
DISPLAY LEFT (-1450 850);
DISPLAY 1.042553 (-1450 850);
PAINT PURPLE (-1450 850);
FORCENOTE
TP FAB1 CHANGE RES 0531
(-2350 1225) 0;
DISPLAY LEFT (-2350 1225);
DISPLAY 1.021277 (-2350 1225);
PAINT RED (-2350 1225);
FORCENOTE
COMPENSATION TYPE III
(-2975 2150) 0;
DISPLAY LEFT (-2975 2150);
DISPLAY 1.042553 (-2975 2150);
PAINT PURPLE (-2975 2150);
FORCENOTE
12A OC
(-5195 1630) 0;
DISPLAY LEFT (-5195 1630);
PAINT PURPLE (-5195 1630);
FORCENOTE
6.25MS
(-5345 2080) 0;
DISPLAY LEFT (-5345 2080);
PAINT PURPLE (-5345 2080);
FORCENOTE
(0.4V/MS)
(-5370 2030) 0;
DISPLAY LEFT (-5370 2030);
PAINT PURPLE (-5370 2030);
FORCENOTE
TP FAB3 CHANGE CAP 0823
(-5250 1250) 0;
DISPLAY LEFT (-5250 1250);
DISPLAY 0.638298 (-5250 1250);
PAINT RED (-5250 1250);
FORCENOTE
TP FAB1 CHANGE CAP 0422
(-5975 1950) 0;
DISPLAY LEFT (-5975 1950);
DISPLAY 1.021277 (-5975 1950);
PAINT RED (-5975 1950);
FORCENOTE
RIPPLE GUIDELINE = +/- 1.0%
(-1975 4475) 0;
DISPLAY LEFT (-1975 4475);
DISPLAY 1.021277 (-1975 4475);
PAINT PURPLE (-1975 4475);
FORCENOTE
PUT TOGETHER
(-7350 4375) 0;
DISPLAY LEFT (-7350 4375);
DISPLAY 0.808511 (-7350 4375);
PAINT PURPLE (-7350 4375);
FORCENOTE
PLACE ON
(-4100 4425) 0;
DISPLAY LEFT (-4100 4425);
DISPLAY 1.042553 (-4100 4425);
PAINT PURPLE (-4100 4425);
FORCENOTE
CAPS TO BE PLACED BETWEEN DIMMS
(-7820 1055) 0;
DISPLAY LEFT (-7820 1055);
DISPLAY 1.021277 (-7820 1055);
PAINT PURPLE (-7820 1055);
FORCENOTE
SW FREQ =  500KHZ
(-1975 4125) 0;
DISPLAY LEFT (-1975 4125);
DISPLAY 1.021277 (-1975 4125);
PAINT PURPLE (-1975 4125);
QUIT
